G04 ================== begin FILE IDENTIFICATION RECORD ==================*
G04 Layout Name:  F:/<user>/2022/FB/R4006-TIMING/brd/gerber-3/R4006-B0001-02_R01.brd*
G04 Film Name:    R4006-B0001-02_R01_L02*
G04 File Format:  Gerber RS274X*
G04 File Origin:  Cadence Allegro 17.2-S079*
G04 Origin Date:  Fri Feb 25 18:14:43 2022*
G04 *
G04 Layer:  ETCH/L02_GND1*
G04 Layer:  PIN/L02_GND1*
G04 Layer:  VIA CLASS/L02_GND1*
G04 Layer:  MANUFACTURING/L02_GND1*
G04 Layer:  MANUFACTURING/CELESTICA_LEGEND*
G04 *
G04 Offset:    (0.00 0.00)*
G04 Mirror:    No*
G04 Mode:      Negative*
G04 Rotation:  0*
G04 FullContactRelief:  No*
G04 UndefLineWidth:     6.00*
G04 ================== end FILE IDENTIFICATION RECORD ====================*
%FSLAX55Y55*MOIN*%
%IR0*IPPOS*OFA0.00000B0.00000*MIA0B0*SFA1.00000B1.00000*%
%AMMACRO17*
4,1,20,-.005,-.04399,
-.009177,-.042751,
-.013075,-.040805,
-.016576,-.038212,
-.019573,-.03505,
-.021977,-.031416,
-.023712,-.02742,
-.024727,-.023183,
-.025,-.0195,
-.025,-.006,
-.02,-.006,
-.02,-.0195,
-.019696,-.022972,
-.018794,-.026338,
-.017321,-.029497,
-.015322,-.032352,
-.012858,-.034816,
-.010003,-.036815,
-.006845,-.038288,
-.005,-.03886,
-.005,-.04399,
270.*
4,1,20,.005,-.04399,
.005,-.03886,
.008286,-.037699,
.01132,-.035985,
.014011,-.033769,
.016276,-.031121,
.018047,-.028119,
.019269,-.024855,
.019907,-.021429,
.02,-.0195,
.02,-.006,
.025,-.006,
.025,-.0195,
.02462,-.02384,
.023493,-.028048,
.021651,-.031997,
.019153,-.035566,
.016072,-.038647,
.012503,-.041145,
.008554,-.042987,
.005,-.04399,
270.*
4,1,20,-.025,.006,
-.025,.0195,
-.02462,.02384,
-.023493,.028048,
-.021651,.031997,
-.019153,.035566,
-.016072,.038647,
-.012503,.041145,
-.008554,.042987,
-.005,.04399,
-.005,.03886,
-.008286,.037699,
-.01132,.035985,
-.014011,.033769,
-.016276,.031121,
-.018047,.028119,
-.019269,.024855,
-.019907,.021429,
-.02,.0195,
-.02,.006,
-.025,.006,
270.*
4,1,20,.02,.006,
.02,.0195,
.019696,.022972,
.018794,.026338,
.017321,.029497,
.015322,.032352,
.012858,.034816,
.010003,.036815,
.006845,.038288,
.005,.03886,
.005,.04399,
.009177,.042751,
.013075,.040805,
.016576,.038212,
.019573,.03505,
.021977,.031416,
.023712,.02742,
.024727,.023183,
.025,.0195,
.025,.006,
.02,.006,
270.*
%
%ADD17MACRO17*%
%ADD22C,.03*%
%ADD16C,.02*%
%ADD12C,.032*%
%ADD14C,.024*%
%ADD20C,.026*%
%ADD21C,.028*%
%ADD15C,.082*%
%ADD10C,.018*%
%ADD19C,.039*%
%ADD28C,.099*%
%AMMACRO24*
4,1,18,.03817,.02827,
.042499,.021212,
.045537,.01351,
.047191,.005398,
.047412,-.002879,
.046191,-.011068,
.043568,-.018921,
.03962,-.026199,
.03817,-.02827,
.04174,-.03184,
.046635,-.024108,
.050113,-.015644,
.052068,-.006704,
.052441,.002439,
.051221,.011508,
.048444,.020228,
.044196,.028333,
.04174,.03184,
.03817,.02827,
0.0*
4,1,18,.02827,-.03817,
.021212,-.042499,
.01351,-.045537,
.005398,-.047191,
-.002879,-.047412,
-.011068,-.046191,
-.018921,-.043568,
-.026199,-.03962,
-.02827,-.03817,
-.03184,-.04174,
-.024108,-.046635,
-.015644,-.050113,
-.006704,-.052068,
.002439,-.052441,
.011508,-.051221,
.020228,-.048444,
.028333,-.044196,
.03184,-.04174,
.02827,-.03817,
0.0*
4,1,18,-.03817,-.02827,
-.042499,-.021212,
-.045537,-.01351,
-.047191,-.005398,
-.047412,.002879,
-.046191,.011068,
-.043568,.018921,
-.03962,.026199,
-.03817,.02827,
-.04174,.03184,
-.046635,.024108,
-.050113,.015644,
-.052068,.006704,
-.052441,-.002439,
-.051221,-.011508,
-.048444,-.020228,
-.044196,-.028333,
-.04174,-.03184,
-.03817,-.02827,
0.0*
4,1,18,-.02827,.03817,
-.021212,.042499,
-.01351,.045537,
-.005398,.047191,
.002879,.047412,
.011068,.046191,
.018921,.043568,
.026199,.03962,
.02827,.03817,
.03184,.04174,
.024108,.046635,
.015644,.050113,
.006704,.052068,
-.002439,.052441,
-.011508,.051221,
-.020228,.048444,
-.028333,.044196,
-.03184,.04174,
-.02827,.03817,
0.0*
%
%ADD24MACRO24*%
%AMMACRO31*
4,1,17,.0205,.01342,
.022519,.009656,
.023854,.005599,
.024464,.001372,
.02433,-.002897,
.023457,-.007078,
.021872,-.011044,
.0205,-.01342,
.02409,-.01702,
.02668,-.012578,
.028458,-.007754,
.029373,-.002695,
.029394,.002447,
.028523,.007514,
.026785,.012353,
.024233,.016816,
.02409,.01702,
.0205,.01342,
90.*
4,1,17,.01342,-.0205,
.009656,-.022519,
.005599,-.023854,
.001372,-.024464,
-.002897,-.02433,
-.007078,-.023457,
-.011044,-.021872,
-.01342,-.0205,
-.01702,-.02409,
-.012578,-.02668,
-.007754,-.028458,
-.002695,-.029373,
.002447,-.029394,
.007514,-.028523,
.012353,-.026785,
.016816,-.024233,
.01702,-.02409,
.01342,-.0205,
90.*
4,1,17,-.0205,-.01342,
-.022519,-.009656,
-.023854,-.005599,
-.024464,-.001372,
-.02433,.002897,
-.023457,.007078,
-.021872,.011044,
-.0205,.01342,
-.02409,.01702,
-.02668,.012578,
-.028458,.007754,
-.029373,.002695,
-.029394,-.002447,
-.028523,-.007514,
-.026785,-.012353,
-.024233,-.016816,
-.02409,-.01702,
-.0205,-.01342,
90.*
4,1,17,-.01342,.0205,
-.009656,.022519,
-.005599,.023854,
-.001372,.024464,
.002897,.02433,
.007078,.023457,
.011044,.021872,
.01342,.0205,
.01702,.02409,
.012578,.02668,
.007754,.028458,
.002695,.029373,
-.002447,.029394,
-.007514,.028523,
-.012353,.026785,
-.016816,.024233,
-.01702,.02409,
-.01342,.0205,
90.*
%
%ADD31MACRO31*%
%AMMACRO26*
4,1,18,.07318,.05409,
.081461,.040561,
.087267,.025799,
.090421,.010253,
.090828,-.005604,
.088475,-.021291,
.083433,-.036331,
.075857,-.050267,
.07318,-.05409,
.07675,-.05766,
.085597,-.043457,
.091842,-.027933,
.095297,-.01156,
.095857,.005164,
.093504,.021731,
.08831,.037637,
.080433,.052401,
.07675,.05766,
.07318,.05409,
0.0*
4,1,18,.05409,-.07318,
.040561,-.081461,
.025799,-.087267,
.010253,-.090421,
-.005604,-.090828,
-.021291,-.088475,
-.036331,-.083433,
-.050267,-.075857,
-.05409,-.07318,
-.05766,-.07675,
-.043457,-.085597,
-.027933,-.091842,
-.01156,-.095297,
.005164,-.095857,
.021731,-.093504,
.037637,-.08831,
.052401,-.080433,
.05766,-.07675,
.05409,-.07318,
0.0*
4,1,18,-.07318,-.05409,
-.081461,-.040561,
-.087267,-.025799,
-.090421,-.010253,
-.090828,.005604,
-.088475,.021291,
-.083433,.036331,
-.075857,.050267,
-.07318,.05409,
-.07675,.05766,
-.085597,.043457,
-.091842,.027933,
-.095297,.01156,
-.095857,-.005164,
-.093504,-.021731,
-.08831,-.037637,
-.080433,-.052401,
-.07675,-.05766,
-.07318,-.05409,
0.0*
4,1,18,-.05409,.07318,
-.040561,.081461,
-.025799,.087267,
-.010253,.090421,
.005604,.090828,
.021291,.088475,
.036331,.083433,
.050267,.075857,
.05409,.07318,
.05766,.07675,
.043457,.085597,
.027933,.091842,
.01156,.095297,
-.005164,.095857,
-.021731,.093504,
-.037637,.08831,
-.052401,.080433,
-.05766,.07675,
-.05409,.07318,
0.0*
%
%ADD26MACRO26*%
%AMMACRO11*
4,1,18,.03185,.02336,
.035423,.017474,
.037919,.011058,
.039263,.004305,
.039414,-.002578,
.038368,-.009383,
.036155,-.015903,
.032845,-.02194,
.03185,-.02336,
.03542,-.02694,
.03956,-.02038,
.042498,-.013201,
.044145,-.005621,
.04445,.00213,
.043405,.009817,
.041041,.017205,
.03743,.02407,
.03542,.02694,
.03185,.02336,
0.0*
4,1,18,.02336,-.03185,
.017474,-.035423,
.011058,-.037919,
.004305,-.039263,
-.002578,-.039414,
-.009383,-.038368,
-.015903,-.036155,
-.02194,-.032845,
-.02336,-.03185,
-.02694,-.03542,
-.02038,-.03956,
-.013201,-.042498,
-.005621,-.044145,
.00213,-.04445,
.009817,-.043405,
.017205,-.041041,
.02407,-.03743,
.02694,-.03542,
.02336,-.03185,
0.0*
4,1,18,-.03185,-.02336,
-.035423,-.017474,
-.037919,-.011058,
-.039263,-.004305,
-.039414,.002578,
-.038368,.009383,
-.036155,.015903,
-.032845,.02194,
-.03185,.02336,
-.03542,.02694,
-.03956,.02038,
-.042498,.013201,
-.044145,.005621,
-.04445,-.00213,
-.043405,-.009817,
-.041041,-.017205,
-.03743,-.02407,
-.03542,-.02694,
-.03185,-.02336,
0.0*
4,1,18,-.02336,.03185,
-.017474,.035423,
-.011058,.037919,
-.004305,.039263,
.002578,.039414,
.009383,.038368,
.015903,.036155,
.02194,.032845,
.02336,.03185,
.02694,.03542,
.02038,.03956,
.013201,.042498,
.005621,.044145,
-.00213,.04445,
-.009817,.043405,
-.017205,.041041,
-.02407,.03743,
-.02694,.03542,
-.02336,.03185,
0.0*
%
%ADD11MACRO11*%
%AMMACRO30*
4,1,20,-.005,-.03799,
-.009177,-.036751,
-.013075,-.034805,
-.016576,-.032212,
-.019573,-.02905,
-.021977,-.025416,
-.023712,-.02142,
-.024727,-.017183,
-.025,-.0135,
-.025,-.005,
-.02,-.005,
-.02,-.0135,
-.019696,-.016972,
-.018794,-.020338,
-.017321,-.023497,
-.015322,-.026352,
-.012858,-.028816,
-.010003,-.030815,
-.006845,-.032288,
-.005,-.03286,
-.005,-.03799,
90.*
4,1,20,.005,-.03799,
.005,-.03286,
.008286,-.031699,
.01132,-.029985,
.014011,-.027769,
.016276,-.025121,
.018047,-.022119,
.019269,-.018855,
.019907,-.015429,
.02,-.0135,
.02,-.005,
.025,-.005,
.025,-.0135,
.02462,-.01784,
.023493,-.022048,
.021651,-.025997,
.019153,-.029566,
.016072,-.032647,
.012503,-.035145,
.008554,-.036987,
.005,-.03799,
90.*
4,1,20,-.025,.005,
-.025,.0135,
-.02462,.01784,
-.023493,.022048,
-.021651,.025997,
-.019153,.029566,
-.016072,.032647,
-.012503,.035145,
-.008554,.036987,
-.005,.03799,
-.005,.03286,
-.008286,.031699,
-.01132,.029985,
-.014011,.027769,
-.016276,.025121,
-.018047,.022119,
-.019269,.018855,
-.019907,.015429,
-.02,.0135,
-.02,.005,
-.025,.005,
90.*
4,1,20,.02,.005,
.02,.0135,
.019696,.016972,
.018794,.020338,
.017321,.023497,
.015322,.026352,
.012858,.028816,
.010003,.030815,
.006845,.032288,
.005,.03286,
.005,.03799,
.009177,.036751,
.013075,.034805,
.016576,.032212,
.019573,.02905,
.021977,.025416,
.023712,.02142,
.024727,.017183,
.025,.0135,
.025,.005,
.02,.005,
90.*
%
%ADD30MACRO30*%
%ADD23C,.102*%
%ADD13C,.15*%
%ADD29C,.143*%
%ADD25C,.125*%
%AMMACRO18*
4,1,15,.01428,.00721,
.015315,.004621,
.015885,.001891,
.015972,-.000896,
.015574,-.003656,
.014702,-.006305,
.01428,-.00721,
.01796,-.01089,
.019578,-.007606,
.020601,-.004091,
.020999,-.000451,
.020758,.003202,
.019887,.006758,
.018411,.010109,
.01796,.01089,
.01428,.00721,
270.*
4,1,15,.00721,-.01428,
.004621,-.015315,
.001891,-.015885,
-.000896,-.015972,
-.003656,-.015574,
-.006305,-.014702,
-.00721,-.01428,
-.01089,-.01796,
-.007606,-.019578,
-.004091,-.020601,
-.000451,-.020999,
.003202,-.020758,
.006758,-.019887,
.010109,-.018411,
.01089,-.01796,
.00721,-.01428,
270.*
4,1,15,-.01428,-.00721,
-.015315,-.004621,
-.015885,-.001891,
-.015972,.000896,
-.015574,.003656,
-.014702,.006305,
-.01428,.00721,
-.01796,.01089,
-.019578,.007606,
-.020601,.004091,
-.020999,.000451,
-.020758,-.003202,
-.019887,-.006758,
-.018411,-.010109,
-.01796,-.01089,
-.01428,-.00721,
270.*
4,1,15,-.00721,.01428,
-.004621,.015315,
-.001891,.015885,
.000896,.015972,
.003656,.015574,
.006305,.014702,
.00721,.01428,
.01089,.01796,
.007606,.019578,
.004091,.020601,
.000451,.020999,
-.003202,.020758,
-.006758,.019887,
-.010109,.018411,
-.01089,.01796,
-.00721,.01428,
270.*
%
%ADD18MACRO18*%
%AMMACRO27*
4,1,18,.0371,.0272,
.04126,.020344,
.044166,.012871,
.04573,.005006,
.045904,-.003011,
.044684,-.010936,
.042106,-.01853,
.038249,-.02556,
.0371,-.0272,
.04067,-.03077,
.045395,-.02324,
.048741,-.015004,
.050606,-.006313,
.050934,.002571,
.049713,.011376,
.046983,.019836,
.042824,.027693,
.04067,.03077,
.0371,.0272,
270.*
4,1,18,.0272,-.0371,
.020344,-.04126,
.012871,-.044166,
.005006,-.04573,
-.003011,-.045904,
-.010936,-.044684,
-.01853,-.042106,
-.02556,-.038249,
-.0272,-.0371,
-.03077,-.04067,
-.02324,-.045395,
-.015004,-.048741,
-.006313,-.050606,
.002571,-.050934,
.011376,-.049713,
.019836,-.046983,
.027693,-.042824,
.03077,-.04067,
.0272,-.0371,
270.*
4,1,18,-.0371,-.0272,
-.04126,-.020344,
-.044166,-.012871,
-.04573,-.005006,
-.045904,.003011,
-.044684,.010936,
-.042106,.01853,
-.038249,.02556,
-.0371,.0272,
-.04067,.03077,
-.045395,.02324,
-.048741,.015004,
-.050606,.006313,
-.050934,-.002571,
-.049713,-.011376,
-.046983,-.019836,
-.042824,-.027693,
-.04067,-.03077,
-.0371,-.0272,
270.*
4,1,18,-.0272,.0371,
-.020344,.04126,
-.012871,.044166,
-.005006,.04573,
.003011,.045904,
.010936,.044684,
.01853,.042106,
.02556,.038249,
.0272,.0371,
.03077,.04067,
.02324,.045395,
.015004,.048741,
.006313,.050606,
-.002571,.050934,
-.011376,.049713,
-.019836,.046983,
-.027693,.042824,
-.03077,.04067,
-.0272,.0371,
270.*
%
%ADD27MACRO27*%
%ADD32C,.01*%
%ADD33C,.005*%
%ADD34C,.006*%
%ADD43R,.03702X.00802*%
%ADD42R,.03702X.00804*%
%ADD37C,.01976*%
%ADD55R,.07002X.03002*%
%ADD47R,.07104X.01002*%
%ADD56R,.07002X.03004*%
%ADD50R,.07004X.03002*%
%ADD45R,.07104X.01004*%
%ADD61C,.40006*%
%ADD60R,.07004X.03004*%
%ADD48R,.03004X.07004*%
%ADD51R,.02002X.04704*%
%ADD54R,.02802X.06002*%
%ADD52R,.05304X.01602*%
%ADD41R,.02004X.04704*%
%ADD38C,.12406*%
%ADD35R,.01204X.06404*%
%ADD59R,.06002X.02804*%
%ADD49R,.06004X.02802*%
%ADD44R,.02802X.06004*%
%ADD57R,.01206X.06404*%
%ADD53R,.05304X.01604*%
%ADD58R,.06004X.02804*%
%ADD46R,.02804X.02404*%
%ADD36R,.02404X.02804*%
%ADD39C,.14906*%
%ADD40C,.16806*%
G75*
%LPD*%
G75*
G36*
G01X-10000Y-10000D02*
X670039D01*
Y447598D01*
X-10000D01*
Y-10000D01*
G37*
%LPC*%
G75*
G36*
G01X3937Y434594D02*
X656102D01*
G02X657035Y433661I0J-933D01*
G01Y287647D01*
G03X652239Y282678I177J-4969D01*
G01Y241437D01*
G03X657035Y236468I4972J0D01*
G01Y54134D01*
G02X656102Y53201I-933J0D01*
G01X316142D01*
G03X309201Y46260I0J-6941D01*
G01Y26200D01*
X231744D01*
Y29331D01*
G03X218256I-6744J0D01*
G01Y26200D01*
X180169D01*
Y43012D01*
G03X159791I-10189J0D01*
G01Y21654D01*
G02X158858Y20721I-933J0D01*
G01X135236D01*
G02X134303Y21654I0J933D01*
G01Y46260D01*
G03X127362Y53201I-6941J0D01*
G01X62992D01*
G03X56051Y46260I0J-6941D01*
G01Y21654D01*
G02X55118Y20721I-933J0D01*
G01X3937D01*
G02X3004Y21654I0J933D01*
G01Y433661D01*
G02X3937Y434594I933J0D01*
G37*
%LPD*%
G75*
G36*
G01X465326Y132496D02*
X465933D01*
G02Y129890I0J-1303D01*
G01X461996D01*
G02Y132496I0J1303D01*
G01X462604D01*
G03X462996Y132972I-1J400D01*
G02X462978Y133158I969J188D01*
G01Y133161D01*
G02X464952I987J0D01*
G01Y133158D01*
G02X464934Y132972I-987J2D01*
G03X465326Y132496I393J-76D01*
G37*
G36*
G01X398397Y163992D02*
X399004D01*
G02Y161388I0J-1302D01*
G01X395067D01*
G02Y163992I0J1302D01*
G01X395673D01*
G03X396066Y164469I0J400D01*
G02X396048Y164655I969J188D01*
G01Y164658D01*
G02X398022I987J0D01*
G01Y164655D01*
G02X398004Y164469I-987J2D01*
G03X398397Y163992I393J-77D01*
G37*
G36*
G01X390522Y167930D02*
X391130D01*
G02Y165324I0J-1303D01*
G01X387193D01*
G02Y167930I0J1303D01*
G01X387800D01*
G03X388192Y168406I-1J400D01*
G02X388174Y168592I969J188D01*
G01Y168595D01*
G02X390148I987J0D01*
G01Y168592D01*
G02X390130Y168406I-987J2D01*
G03X390522Y167930I393J-76D01*
G37*
G36*
G01X406271D02*
X406879D01*
G02Y165324I0J-1303D01*
G01X402942D01*
G02Y167930I0J1303D01*
G01X403549D01*
G03X403941Y168406I-1J400D01*
G02X403922Y168595I969J193D01*
G02X405898I988J0D01*
G02X405879Y168406I-988J4D01*
G03X406271Y167930I393J-76D01*
G37*
G36*
G01X398397Y171866D02*
X399004D01*
G02Y169262I0J-1302D01*
G01X395067D01*
G02Y171866I0J1302D01*
G01X395673D01*
G03X396066Y172343I0J400D01*
G02X396048Y172529I969J188D01*
G01Y172532D01*
G02X398022I987J0D01*
G01Y172529D01*
G02X398004Y172343I-987J2D01*
G03X398397Y171866I393J-77D01*
G37*
G36*
G01X446248Y185008D02*
X445641D01*
G03X445249Y184532I1J-400D01*
G02X445268Y184343I-969J-193D01*
G02X443292I-988J0D01*
G02X443311Y184532I988J-4D01*
G03X442919Y185008I-393J76D01*
G01X442311D01*
G02Y187614I0J1303D01*
G01X446248D01*
G02Y185008I0J-1303D01*
G37*
G36*
G01X449186Y144784D02*
G03X449579Y144308I393J-76D01*
G01X450185D01*
G02Y141702I0J-1303D01*
G01X446248D01*
G02Y144308I0J1303D01*
G01X446855D01*
G03X447248Y144784I0J400D01*
G02X447230Y144970I969J188D01*
G01Y144973D01*
G02X449204I987J0D01*
G01Y144970D01*
G02X449186Y144784I-987J2D01*
G37*
G36*
G01X600696Y115350D02*
G02X617500Y124503I16804J-10849D01*
G02X637503Y104500I0J-20003D01*
G02X636283Y97621I-20004J0D01*
G02X636500Y96501I-2783J-1120D01*
G01Y96500D01*
G02X634273Y93601I-3000J0D01*
G02X617500Y84497I-16773J10899D01*
G02X597497Y104500I0J20003D01*
G02X598437Y110560I20003J0D01*
G02X597846Y112349I2413J1789D01*
G01Y112350D01*
G02X600696Y115350I3004J0D01*
G37*
G36*
G01X390148Y160718D02*
G02X390130Y160532I-987J2D01*
G03X390522Y160056I393J-76D01*
G01X391130D01*
G02Y157450I0J-1303D01*
G01X387193D01*
G02Y160056I0J1303D01*
G01X387800D01*
G03X388192Y160532I-1J400D01*
G02X388174Y160718I969J188D01*
G01Y160721D01*
G02X390148I987J0D01*
G01Y160718D01*
G37*
G36*
G01X405879Y152658D02*
G03X406272Y152182I393J-76D01*
G01X406879D01*
G02Y149576I0J-1303D01*
G01X402942D01*
G02Y152182I0J1303D01*
G01X403548D01*
G03X403941Y152658I0J400D01*
G02X403922Y152847I969J193D01*
G02X405898I988J0D01*
G02X405879Y152658I-988J4D01*
G37*
G36*
G01X310516Y87500D02*
X312500Y89484D01*
X316747Y85237D01*
X314763Y83253D01*
X310516Y87500D01*
G37*
G36*
G01X472028Y138067D02*
G03X472504Y138460I76J393D01*
G01Y139067D01*
G02X475110I1303J0D01*
G01Y135130D01*
G02X472504I-1303J0D01*
G01Y135736D01*
G03X472028Y136129I-400J0D01*
G02X471839Y136110I-193J969D01*
G02Y138086I0J988D01*
G02X472028Y138067I-4J-988D01*
G37*
G36*
G01X387799Y144308D02*
G03X388192Y144784I0J400D01*
G02X388174Y144973I969J188D01*
G02X390148I987J0D01*
G02X390130Y144784I-987J-1D01*
G03X390523Y144308I393J-76D01*
G01X391130D01*
G02Y141702I0J-1303D01*
G01X387193D01*
G02Y144308I0J1303D01*
G01X387799D01*
G37*
G36*
G01X395673Y148244D02*
G03X396066Y148721I0J400D01*
G02X396048Y148910I969J188D01*
G02X398022I987J0D01*
G02X398004Y148721I-987J-1D01*
G03X398397Y148244I393J-77D01*
G01X399004D01*
G02Y145640I0J-1302D01*
G01X395067D01*
G02Y148244I0J1302D01*
G01X395673D01*
G37*
G36*
G01X470477D02*
G03X470870Y148721I0J400D01*
G02X470852Y148910I969J188D01*
G02X472826I987J0D01*
G02X472808Y148721I-987J-1D01*
G03X473201Y148244I393J-77D01*
G01X473807D01*
G02Y145640I0J-1302D01*
G01X469870D01*
G02Y148244I0J1302D01*
G01X470477D01*
G37*
G36*
G01X387799Y152182D02*
G03X388192Y152658I0J400D01*
G02X388174Y152847I969J188D01*
G02X390148I987J0D01*
G02X390130Y152658I-987J-1D01*
G03X390523Y152182I393J-76D01*
G01X391130D01*
G02Y149576I0J-1303D01*
G01X387193D01*
G02Y152182I0J1303D01*
G01X387799D01*
G37*
G36*
G01X395673Y156118D02*
G03X396066Y156595I0J400D01*
G02X396048Y156784I969J188D01*
G02X398022I987J0D01*
G02X398004Y156595I-987J-1D01*
G03X398397Y156118I393J-77D01*
G01X399004D01*
G02Y153514I0J-1302D01*
G01X395067D01*
G02Y156118I0J1302D01*
G01X395673D01*
G37*
G54D43*
X358207Y189187D03*
Y193911D03*
G54D42*
X350595Y190762D03*
X358207D03*
X350595Y192336D03*
X358207D03*
G54D37*
X408847Y152847D03*
X393098Y160721D03*
X408847Y168595D03*
X400973Y172532D03*
Y164658D03*
X393098Y168595D03*
X440343Y184343D03*
X460028Y133161D03*
X444280Y144973D03*
X471839Y141035D03*
X467902Y148910D03*
X393098Y144973D03*
X400973Y148910D03*
X393098Y152847D03*
X400973Y156784D03*
G54D55*
X439251Y116599D03*
X455731Y122167D03*
X353065Y104707D03*
G54D47*
X276986Y186995D03*
Y188963D03*
G54D56*
X281801Y198700D03*
G54D50*
X403250Y116099D03*
G54D45*
X276986Y177152D03*
Y175184D03*
Y190932D03*
X292734D03*
Y192900D03*
X276986D03*
G54D61*
X599000Y209400D03*
G54D60*
X343400Y108500D03*
G54D48*
X284500Y185900D03*
X240508Y71500D03*
X337500Y117800D03*
G54D51*
X630729Y220184D03*
X623249D03*
G54D54*
X365101Y189959D03*
X345301Y191499D03*
G54D52*
X641050Y208465D03*
G54D41*
X68260Y350650D03*
X75740D03*
G54D38*
X268567Y112143D03*
X143567Y106043D03*
X146067Y268043D03*
X268567Y255943D03*
G54D35*
X113284Y357800D03*
G54D59*
X268307Y76300D03*
X283455D03*
G54D49*
X324310Y190299D03*
G54D44*
X295835Y46500D03*
X280087Y36900D03*
X295835D03*
X264339D03*
X619961Y226074D03*
G54D57*
X115253Y357800D03*
G54D53*
X641050Y211024D03*
G54D58*
X71900Y357500D03*
X108900Y382500D03*
X248622Y76300D03*
X364100Y92000D03*
G54D46*
X312300Y175000D03*
X316500D03*
X311900Y185000D03*
X312300Y180000D03*
X311900Y189500D03*
X316500Y180000D03*
X316100Y189500D03*
Y185000D03*
X321000Y196500D03*
X316800D03*
X321000Y201500D03*
X316800D03*
X321000Y206000D03*
X316800D03*
X321000Y211000D03*
X316800D03*
G54D36*
X110500Y368900D03*
X115500Y373100D03*
X325900Y206400D03*
Y210600D03*
Y201100D03*
Y196900D03*
X115500Y368900D03*
X110500Y373100D03*
G54D39*
X640039Y417835D03*
X29528Y36811D03*
Y373031D03*
X640039Y65354D03*
G54D40*
X634055Y367519D03*
Y334449D03*
G54D17*
X24807Y335985D03*
Y347245D03*
X43705Y331655D03*
Y351576D03*
G54D22*
X76100Y154400D03*
X75950Y164200D03*
X73600Y252500D03*
X68600Y274000D03*
X75500Y282500D03*
X63800Y274000D03*
X70500Y419000D03*
X75580Y419004D03*
X88300Y163900D03*
X98000Y420000D03*
X90000Y420500D03*
X85500D03*
X112880Y73020D03*
X126000Y67000D03*
Y62000D03*
X131500Y290500D03*
X148500Y62500D03*
X139500D03*
X145900Y75200D03*
X142070Y77900D03*
X142000Y69535D03*
X136000Y290500D03*
X138250Y372250D03*
X148500Y376000D03*
X138500Y387500D03*
X153500Y390500D03*
X163300Y382900D03*
X151100Y386300D03*
X152100Y399300D03*
X151530Y406300D03*
X153150Y394590D03*
X160600Y417400D03*
X152200Y416300D03*
X183170Y56390D03*
X180620Y77890D03*
X180390Y70720D03*
X180910Y63390D03*
X187598Y36900D03*
X189500Y33000D03*
X186000D03*
X187598Y28900D03*
X191535Y41200D03*
X198135Y36500D03*
X195000Y54550D03*
X203000Y75000D03*
X196497Y76502D03*
X210500Y30500D03*
X207880Y78740D03*
X214810Y78810D03*
X212800Y289500D03*
X218500Y301700D03*
X213500D03*
X208500D03*
X224500Y302000D03*
X222000Y330000D03*
X254527Y33900D03*
X240508Y69900D03*
Y73100D03*
X263300Y52200D03*
X284500Y184300D03*
Y187500D03*
X283400Y198700D03*
X280200D03*
X289600Y330100D03*
X307300Y61300D03*
X298700Y327000D03*
Y323500D03*
X293200Y329500D03*
X322200Y320500D03*
X310600Y335000D03*
X322200Y338500D03*
X341799Y108500D03*
X337500Y116200D03*
Y119400D03*
X349000Y82500D03*
X344999Y108500D03*
X351464Y104707D03*
X354664D03*
X352300Y175000D03*
X358400Y182700D03*
X345930Y217000D03*
X354800Y285600D03*
X355000Y328000D03*
X375500Y350500D03*
X380400Y81600D03*
X381700Y92400D03*
X383128Y178372D03*
X383000Y346600D03*
X388500Y391000D03*
X393500D03*
X388500Y400000D03*
X393500D03*
X393000Y418500D03*
X401650Y116099D03*
X404850D03*
X405463Y383000D03*
X410463D03*
X398500Y391000D03*
Y400000D03*
X403000Y418500D03*
X398000D03*
X415463Y383000D03*
X414000Y419000D03*
X422337Y424000D03*
X416800D03*
X437650Y116599D03*
X440850D03*
X442500Y336089D03*
X439500Y341500D03*
X443000Y386500D03*
X432000Y396500D03*
X457330Y122167D03*
X454130D03*
X490970Y133500D03*
Y138500D03*
X488500Y359000D03*
X500500Y271100D03*
X500000Y278799D03*
X533000Y95000D03*
Y99500D03*
X522400Y270700D03*
X522600Y276200D03*
X528500Y299000D03*
X532300Y425700D03*
X549500Y69400D03*
X548158Y228033D03*
X545250Y256300D03*
X539977Y275124D03*
X540318Y270436D03*
X537500Y296607D03*
X568600Y76000D03*
X553122Y227979D03*
X559500Y228000D03*
X566700Y227500D03*
X552000Y367597D03*
Y371141D03*
X555200Y367597D03*
Y371141D03*
X552000Y374684D03*
Y378227D03*
X555200D03*
Y374684D03*
X572500Y60301D03*
X572870Y67570D03*
X577100Y227900D03*
X581400Y262100D03*
Y272100D03*
Y282100D03*
X581500Y302100D03*
X576200Y342500D03*
X597000Y199900D03*
X591902Y200300D03*
X601902Y200100D03*
X594153Y220500D03*
X589953Y236600D03*
X591000Y261500D03*
X590500Y301500D03*
X606902Y200400D03*
X633500Y205906D03*
X625800Y215874D03*
X633000Y267000D03*
G54D12*
X11264Y152264D03*
X9000Y279000D03*
Y286000D03*
X12500Y91000D03*
Y96000D03*
Y101000D03*
Y106000D03*
X19100Y148798D03*
X23600D03*
X28100D03*
X13620Y148720D03*
X13000Y157000D03*
X12500Y162000D03*
Y209500D03*
Y204500D03*
Y214500D03*
Y219500D03*
X11963Y266437D03*
X19000Y262500D03*
X24200Y262508D03*
X28700D03*
X12500Y261500D03*
X15000Y279000D03*
X28700Y274300D03*
X13000Y273327D03*
X28500Y302000D03*
X28000Y296500D03*
X16000Y297500D03*
X24100Y310900D03*
X18000Y314500D03*
X13000Y318700D03*
X11976Y323524D03*
X28000Y327000D03*
X44500Y73500D03*
X45500Y104390D03*
X41500Y127500D03*
X41409Y132591D03*
X41600Y148798D03*
X32600Y148700D03*
X37100Y148798D03*
X45500Y182500D03*
X45000Y213000D03*
X46000Y219500D03*
X40500Y262000D03*
X33200Y262508D03*
X43000Y255500D03*
X37400Y282900D03*
X29000Y291500D03*
X43000Y314500D03*
X33000D03*
X44500Y309000D03*
X39500D03*
X34500D03*
X35500Y327000D03*
X59600Y60200D03*
X55500Y59000D03*
X50500Y60228D03*
X60100Y73000D03*
X57000Y83500D03*
X51500D03*
X50500Y104800D03*
X59000Y96500D03*
X62500Y100500D03*
X57500Y101500D03*
X62500Y117000D03*
X48390Y128312D03*
X53740Y126000D03*
X55922Y140543D03*
X46500Y133000D03*
X47500Y140500D03*
X60500Y152000D03*
X51400Y161600D03*
X54130Y152500D03*
X60600Y157000D03*
X48957Y153619D03*
X53500Y183500D03*
X58000Y213500D03*
X54000D03*
X48000Y200500D03*
X53000D03*
X63000Y206000D03*
Y210500D03*
Y215000D03*
X49600Y213455D03*
X51452Y219900D03*
X53200Y240187D03*
X54590Y266870D03*
X48232Y264530D03*
X48500Y252500D03*
X55200Y253500D03*
X52500Y278000D03*
X52800Y272000D03*
X62000Y307000D03*
Y323500D03*
X55000Y336000D03*
Y355400D03*
X62500Y365000D03*
Y369000D03*
Y373000D03*
Y378000D03*
Y382000D03*
X60300Y407100D03*
Y401100D03*
Y395100D03*
Y413100D03*
X71500Y77000D03*
X76400Y87200D03*
X76321Y78300D03*
X78500Y82250D03*
X73500Y112500D03*
X67000Y109000D03*
X79000Y100500D03*
X74000D03*
X67500Y114500D03*
X68000Y119000D03*
X73500D03*
X69500Y130000D03*
X74000D03*
X75000Y141700D03*
X64445Y168945D03*
X69000Y187500D03*
Y193000D03*
X69023Y198524D03*
X67400Y227100D03*
X71400Y232900D03*
X68000Y235500D03*
X67700Y240200D03*
X72400Y264600D03*
X69500Y257800D03*
X64248Y258000D03*
X64500Y296750D03*
X78000Y291500D03*
X66000Y318500D03*
X79000Y315500D03*
X66000Y323500D03*
X78635Y324492D03*
X79500Y341790D03*
Y348500D03*
X72000Y346300D03*
X73000Y365000D03*
X69500D03*
X66000D03*
X66500Y382000D03*
X70500D03*
X80700Y399200D03*
Y404200D03*
X71300D03*
Y399200D03*
X76000D03*
Y404200D03*
X71300Y394200D03*
X76000D03*
X80700D03*
X64300Y407600D03*
Y401600D03*
Y395600D03*
X80500Y420500D03*
X80700Y409200D03*
X76000D03*
X71300D03*
X64300Y413600D03*
X86000Y63100D03*
X84200Y75000D03*
X82100Y79300D03*
X96500Y98000D03*
X92250Y97750D03*
X89000Y110500D03*
X93500D03*
X90500Y105000D03*
X84000Y100500D03*
X87000Y130000D03*
Y120000D03*
X93500Y125000D03*
X87000Y125500D03*
X93500Y130000D03*
X90500Y144500D03*
X95500Y145500D03*
X96500Y140000D03*
X91500D03*
X88400Y154900D03*
X93900Y155200D03*
X95200Y151000D03*
X88500Y149000D03*
X94500Y163000D03*
X98500Y159000D03*
X91000Y181500D03*
X88250Y177250D03*
X83500Y178000D03*
X97500Y172000D03*
X98500Y165500D03*
X92000Y173000D03*
X83500D03*
X95500Y192000D03*
X83500Y193000D03*
Y188500D03*
X90500D03*
X94500Y197000D03*
X90500Y193500D03*
X97500Y214000D03*
X84500Y218000D03*
X95700Y227500D03*
X98500Y218500D03*
X96000Y241000D03*
X85700Y236500D03*
X96500Y235500D03*
X98500Y256661D03*
X83200Y260300D03*
X86900Y267200D03*
X95900Y278900D03*
X94500Y312500D03*
X95000Y321500D03*
X82500Y339000D03*
X82951Y327940D03*
X97500Y341000D03*
X95100Y351900D03*
X83000Y352500D03*
Y344500D03*
X95000D03*
X82800Y364600D03*
X94500Y373000D03*
Y369000D03*
Y364500D03*
X90500D03*
X86500D03*
X91500Y359500D03*
X83500Y360000D03*
X82800Y384600D03*
X94500Y380500D03*
X94000Y384500D03*
X90500D03*
X86500D03*
X94500Y376500D03*
X85400Y404200D03*
Y399200D03*
Y394200D03*
X96800Y408100D03*
X92800D03*
Y402100D03*
X96800D03*
Y396100D03*
X92800D03*
X85400Y409200D03*
X96800Y414100D03*
X92800D03*
X111330Y59810D03*
X99000Y175500D03*
Y188500D03*
Y197500D03*
Y206500D03*
Y201500D03*
Y260025D03*
X112500Y302000D03*
X107500D03*
X112500Y290000D03*
X102500D03*
Y302000D03*
X105410Y318500D03*
X115253Y306247D03*
X101500Y341000D03*
X104019Y347425D03*
X103000Y351500D03*
X113000Y344500D03*
X114000Y352000D03*
X104500Y377000D03*
X125000Y76500D03*
X126000Y72000D03*
X117500Y290000D03*
X129000Y321500D03*
X126000Y318000D03*
X129500Y328000D03*
X130000Y349664D03*
X119000Y352000D03*
X124500D03*
X140100Y306900D03*
X135000Y312000D03*
X149500Y311034D03*
X140700Y320000D03*
X146000Y334000D03*
X141916Y333916D03*
X137000Y364000D03*
X145000Y359000D03*
X141000Y379500D03*
X148500Y380000D03*
X145000Y378000D03*
X135200Y408400D03*
X140000Y401000D03*
X135100Y412600D03*
X143500Y418000D03*
X153270Y58400D03*
X151200Y75191D03*
X160500Y75500D03*
Y71500D03*
X156800Y301100D03*
X156600Y295000D03*
X156000Y320500D03*
Y316500D03*
Y325000D03*
Y329000D03*
X159100Y354600D03*
X166700Y343800D03*
X151500Y358000D03*
X159100Y382600D03*
X163600Y378600D03*
X157900Y387400D03*
X158500Y405200D03*
X160582Y410000D03*
X160550Y413400D03*
X151700Y411300D03*
X173170Y70840D03*
X182600Y289500D03*
X179500Y294600D03*
X176500Y290000D03*
X178000Y309500D03*
X173800Y324100D03*
X175000Y394500D03*
X177000Y398000D03*
X188900Y54960D03*
X195900Y332500D03*
X213500Y54000D03*
X208160Y73990D03*
X204770Y67780D03*
X207800Y83010D03*
X219200Y338800D03*
X205000Y348800D03*
Y353800D03*
X215000Y343800D03*
X219000Y348800D03*
Y392500D03*
X215500D03*
X216500Y396000D03*
X220000D03*
X223500Y58250D03*
X231000Y68000D03*
Y71500D03*
X228500Y75500D03*
Y79000D03*
X226500Y334000D03*
X222500Y324500D03*
X238000Y345000D03*
X225500Y347500D03*
X230000D03*
X249000Y290300D03*
X255400Y290100D03*
X247000Y344500D03*
X251000D03*
X255000D03*
X259500Y54700D03*
X259000Y344500D03*
X296400Y70200D03*
X307500Y160500D03*
X303500Y164000D03*
X298284Y175184D03*
X300995Y187611D03*
X297772Y188694D03*
X297000Y310500D03*
X301000Y317000D03*
X293700Y317300D03*
X309000Y164500D03*
X312500Y160500D03*
X320500Y170000D03*
X324000Y227500D03*
Y220750D03*
X312500Y225400D03*
X311900Y229900D03*
Y243400D03*
X312000Y269000D03*
Y256500D03*
Y264500D03*
X317500Y295500D03*
X321000D03*
X324500D03*
X310500Y321000D03*
X312500Y307500D03*
X310600Y326000D03*
X325000Y363000D03*
X320000Y398500D03*
X323000Y401500D03*
X336000Y61060D03*
X340500Y63500D03*
Y87000D03*
X338000Y102500D03*
X332550Y213550D03*
X327923Y221577D03*
X335153Y217875D03*
X333500Y258900D03*
X338500Y259000D03*
X339500Y282000D03*
X341000Y304000D03*
X332500Y306500D03*
X328000D03*
X341400Y323500D03*
X340500Y361300D03*
X332500D03*
X336500D03*
X339200Y380300D03*
X339300Y384000D03*
Y387700D03*
X340500Y391600D03*
X336300Y423200D03*
Y415200D03*
Y419200D03*
X340800Y415200D03*
X349500Y61000D03*
X354500Y60920D03*
X345500Y87000D03*
X354000Y82500D03*
X344000Y103000D03*
X347500Y141500D03*
X350000D03*
X352500D03*
X355000D03*
X357000Y154200D03*
X353482Y154157D03*
X350085Y154300D03*
X346500Y174000D03*
X344500Y181500D03*
X349128Y186628D03*
X344000Y212000D03*
X355500Y218000D03*
Y220500D03*
Y225500D03*
Y223000D03*
X351000Y233243D03*
Y237000D03*
X352500Y260000D03*
X348500D03*
X357680Y271780D03*
X357000Y295500D03*
X356000Y302300D03*
X349000Y295500D03*
X346000Y306500D03*
X351000Y308000D03*
X355000Y337000D03*
X348418Y361300D03*
X344500D03*
X347700Y381600D03*
X347000Y391200D03*
X359800Y397700D03*
X347600Y398800D03*
X348279Y405678D03*
X353000Y416500D03*
X350000Y419500D03*
X349500Y415000D03*
X346000Y416000D03*
X343700Y409900D03*
X348863Y410500D03*
X369310Y109500D03*
X369172Y102828D03*
X362000Y123500D03*
Y128000D03*
X376500Y141000D03*
X374000D03*
X360500Y154500D03*
X374900Y154228D03*
X371400Y154300D03*
X367900Y154228D03*
X367400Y174400D03*
X373649Y185735D03*
X377500Y218500D03*
Y221000D03*
Y226500D03*
Y223500D03*
X373500Y247000D03*
X365500Y246500D03*
X375800Y255200D03*
X376500Y269000D03*
X365000Y268000D03*
X370000Y276000D03*
X374500D03*
X361400Y301500D03*
Y305800D03*
Y309900D03*
X365500Y305900D03*
X375500Y309200D03*
X371000Y326000D03*
X370000Y337000D03*
Y332500D03*
X366000Y350850D03*
X360700Y406200D03*
X364500Y413500D03*
X382286Y86214D03*
X379000Y141000D03*
X382000Y142000D03*
X378400Y154300D03*
X384091Y200091D03*
X379500Y237500D03*
X391900Y246800D03*
X386000D03*
X380100D03*
X386000Y259250D03*
X389400Y281100D03*
X378000Y281000D03*
X382200D03*
X394800Y281300D03*
X383000Y323500D03*
X390000Y338500D03*
X392500Y329100D03*
Y323900D03*
X381000Y365000D03*
X386500D03*
X389500Y370000D03*
X395000D03*
Y360000D03*
X383900Y384600D03*
X379500Y381000D03*
Y375800D03*
Y417500D03*
X407500Y225000D03*
X397800Y246800D03*
X403700D03*
X409300D03*
X400000Y265500D03*
X402000Y303000D03*
X396981Y304482D03*
X407500Y300500D03*
X402500Y308000D03*
X408500Y316500D03*
Y321998D03*
Y311000D03*
X398000Y336500D03*
X410000Y338000D03*
X406610Y353410D03*
X411840Y353620D03*
X409000Y371339D03*
X423000Y72950D03*
X417500Y75000D03*
X425000Y87700D03*
X420900Y246800D03*
X415000D03*
X420900Y259000D03*
X424900Y284300D03*
X423900Y278500D03*
X424900Y292900D03*
X413000Y300500D03*
X429442Y310075D03*
X417500Y337000D03*
X422500Y354500D03*
X428500Y346000D03*
X413500Y373500D03*
X419000D03*
X420500Y366000D03*
X425000Y381000D03*
X420500D03*
X423500Y415500D03*
X436500Y233000D03*
X443500Y231500D03*
X436500Y237500D03*
X439500Y250000D03*
X435000Y250500D03*
X443500Y236500D03*
X440000Y278500D03*
X434600Y278300D03*
X435500Y274500D03*
X445600Y278300D03*
X438150Y283800D03*
X447000Y283000D03*
X433050Y291400D03*
X446000Y294000D03*
X439000Y302000D03*
X434500D03*
X433000Y314320D03*
X435143Y306643D03*
X447000Y321998D03*
X440000Y332500D03*
X434000Y328000D03*
X433000Y353500D03*
X433500Y366500D03*
X433382Y360466D03*
X438500Y364500D03*
X438400Y382400D03*
X430000Y381000D03*
X431000Y406500D03*
Y411500D03*
X460000Y76000D03*
X463500Y92000D03*
X458500Y86500D03*
X448500Y100500D03*
X462500Y117000D03*
X461000Y234500D03*
X457500Y227500D03*
Y223500D03*
X449000Y232500D03*
Y227500D03*
X461000Y230000D03*
X448500Y237500D03*
X457500Y250000D03*
X448500D03*
X457500Y237400D03*
X453000Y250000D03*
X457000Y258500D03*
X459500Y262000D03*
X461500Y268409D03*
X460800Y294200D03*
X461000Y302500D03*
X464500Y298500D03*
X456500Y305500D03*
X454000Y312500D03*
X448500Y311500D03*
X461500Y311000D03*
X451000Y306500D03*
X450900Y330900D03*
X450500Y368500D03*
X453500Y381500D03*
X450000Y416500D03*
Y411500D03*
X478000Y78000D03*
X482000Y83500D03*
X465500Y78500D03*
X475500Y82500D03*
X470500D03*
X481000Y172500D03*
X479246Y178464D03*
X477500Y170500D03*
X481500Y193000D03*
X480288Y203788D03*
X471000Y239000D03*
X477000D03*
X468500Y264500D03*
Y270000D03*
X478500Y346000D03*
X481000Y341000D03*
X470500Y391000D03*
X493700Y79161D03*
X496000Y85000D03*
Y163000D03*
X484000Y166000D03*
X497000Y175000D03*
X485033Y174934D03*
X498060Y185500D03*
X483871Y198241D03*
X496500Y197500D03*
X484000Y185500D03*
X497500Y214000D03*
X485000Y202739D03*
X490500Y216750D03*
X492500Y226000D03*
X497500D03*
X497100Y244700D03*
X497200Y240600D03*
X492300Y240800D03*
X497000Y341000D03*
X495000Y346000D03*
X483501D03*
X488500D03*
X504000Y64500D03*
X508500D03*
X513200Y66000D03*
X503005Y99494D03*
X508000Y105500D03*
Y110500D03*
Y115500D03*
X503860Y124150D03*
X503900Y128690D03*
X514500Y144000D03*
X503950Y133500D03*
X514500Y151000D03*
Y148000D03*
Y154000D03*
Y157000D03*
X501500Y192500D03*
X507000D03*
Y188500D03*
X515500Y201000D03*
X513000Y210500D03*
X511500Y206500D03*
X513500Y215500D03*
X509000D03*
X502200Y240700D03*
X501000Y263500D03*
X509000Y340500D03*
X504500D03*
X514000Y374000D03*
X507500Y394500D03*
X503500D03*
X521500Y60000D03*
X529500Y60500D03*
X526500Y67500D03*
X519500Y75500D03*
X533000Y82000D03*
X519500Y81500D03*
X520000Y87000D03*
X524900Y99000D03*
X522500Y114500D03*
X528710Y227500D03*
X534000Y231500D03*
X525400Y247000D03*
X522000D03*
X524300Y261700D03*
X523900Y257100D03*
X523600Y281100D03*
X531000Y285500D03*
X526000Y295500D03*
X519000Y307500D03*
X517500Y374000D03*
X518000Y382500D03*
X527500Y389100D03*
X532100Y399000D03*
X527500Y397100D03*
Y393100D03*
X522100Y416500D03*
X551500Y59597D03*
X549000Y63500D03*
Y78223D03*
X544300Y87100D03*
X549400Y81600D03*
X536500Y84500D03*
Y79000D03*
X543520Y174970D03*
X542270Y169900D03*
X539770Y174900D03*
Y169900D03*
Y172400D03*
X542270D03*
X545800Y216500D03*
X541000Y216400D03*
X537500Y232000D03*
X548300Y222600D03*
X546500Y240500D03*
X541000Y281500D03*
X539500Y292000D03*
X542000Y296450D03*
X537500Y304000D03*
X539000Y370000D03*
X539300Y365100D03*
X539000Y360000D03*
X543000Y370000D03*
X543300Y365100D03*
X543000Y360000D03*
X540600Y386300D03*
X548829Y416329D03*
X548500Y411000D03*
X538558Y413779D03*
X550369Y427558D03*
X538558D03*
X565933Y102000D03*
X562533Y102001D03*
X553000Y108500D03*
X554600Y202400D03*
X558900Y202500D03*
X566950Y220000D03*
X560000Y240000D03*
X565400Y244700D03*
X562000Y254870D03*
X554400Y267500D03*
X561700Y320300D03*
X556700D03*
X562500Y336100D03*
Y326100D03*
X562000Y331600D03*
X560000Y342100D03*
X568100Y366400D03*
Y361700D03*
X568326Y371200D03*
X563800Y390700D03*
X567500Y386500D03*
X568600Y376000D03*
Y380700D03*
X564400Y396700D03*
X567500Y403000D03*
X555000Y402000D03*
X567126Y417500D03*
X555315D03*
X562180Y413779D03*
Y427558D03*
X586500Y107000D03*
Y112500D03*
X571000Y217900D03*
X576500Y219700D03*
X569943Y223300D03*
X585000Y226500D03*
X578900Y236600D03*
X583000Y297000D03*
X580300Y390700D03*
X576900Y403100D03*
X578937Y417500D03*
X572500Y413500D03*
X584000Y421900D03*
X573991Y427558D03*
X588000Y96500D03*
X600850Y112350D03*
X592000Y127063D03*
X599500Y116500D03*
X592000Y141000D03*
Y146000D03*
Y163000D03*
Y151500D03*
Y157063D03*
Y173000D03*
Y178000D03*
Y168000D03*
X587500Y190000D03*
X594003Y187000D03*
X602500Y183000D03*
X601550Y208450D03*
X596450Y210350D03*
X601953Y218853D03*
X590650Y245680D03*
X604000Y254500D03*
X591000Y271500D03*
Y278500D03*
Y291500D03*
X602500Y404000D03*
X591000D03*
X604000Y398000D03*
X597500Y421900D03*
X602559Y417500D03*
X590748Y418725D03*
X597613Y413779D03*
Y427558D03*
X606902Y186000D03*
X610500Y190500D03*
X614100Y236400D03*
X618650Y249300D03*
X609500Y254500D03*
X614500Y398000D03*
Y403500D03*
X614370Y417500D03*
X609424Y413779D03*
Y427558D03*
X633500Y108000D03*
Y102000D03*
Y96500D03*
X637900Y116900D03*
X622000Y127063D03*
Y141500D03*
Y146500D03*
Y162000D03*
Y151600D03*
Y157000D03*
Y181500D03*
Y175500D03*
X622035Y167063D03*
X628500Y189500D03*
X627500Y205374D03*
X633000Y286500D03*
X647000Y108000D03*
G54D20*
X46000Y82000D03*
X51765Y96600D03*
X79500Y234500D03*
X79600Y248900D03*
X77964Y260100D03*
X75800Y274300D03*
X72000Y271400D03*
X82500Y230500D03*
X84600Y248900D03*
X89600D03*
X82500Y273200D03*
X87100Y271300D03*
X112800Y66600D03*
X243500Y48650D03*
X252700Y44000D03*
X297700Y335100D03*
X324000Y236000D03*
X318000Y268500D03*
X324300Y254700D03*
X327500Y232000D03*
X332600Y246600D03*
X328500Y238645D03*
X327800Y246800D03*
X334350Y282000D03*
X336500Y295000D03*
X336525Y320500D03*
Y325500D03*
X341500Y338500D03*
Y328500D03*
Y333500D03*
X336525Y330500D03*
X342900Y246800D03*
X344000Y295000D03*
X358250Y340050D03*
X361124Y349876D03*
X387193Y143005D03*
X391130D03*
X387193Y150879D03*
X391130D03*
X387193Y158753D03*
X391130D03*
X387193Y166627D03*
X391130D03*
X391600Y304800D03*
X379300Y305000D03*
X383000Y328500D03*
Y333500D03*
X395067Y146942D03*
X399005D03*
X395067Y154816D03*
X399005D03*
X395067Y162690D03*
X399005D03*
X402942Y150879D03*
X406879D03*
X395067Y170564D03*
X399005D03*
X402942Y166627D03*
X406879D03*
X421360Y359970D03*
X446248Y143005D03*
Y186311D03*
X442311D03*
X441500Y297500D03*
X444000Y406500D03*
X431900Y392200D03*
X431169Y401169D03*
X444000Y411500D03*
X461996Y131193D03*
X450185Y143005D03*
X465933Y131193D03*
X473807Y135130D03*
Y139067D03*
Y146942D03*
X469870D03*
X470462Y369462D03*
X470500Y395000D03*
X493500Y359000D03*
X503000Y354600D03*
X550643Y400900D03*
X568000Y356700D03*
X555569Y388051D03*
G54D15*
X16039Y71260D03*
Y128346D03*
Y185433D03*
Y242520D03*
G54D21*
X63500Y84500D03*
X56500Y113000D03*
X54500Y171000D03*
X62000Y199500D03*
X57500Y226500D03*
X63600Y291500D03*
X75500Y62000D03*
X64400Y70000D03*
X64500Y129500D03*
X64700Y251700D03*
X79500Y308500D03*
X71000Y330500D03*
X78000D03*
X73500Y357500D03*
X70300D03*
X94500Y299000D03*
X88500Y303000D03*
X95000Y291500D03*
X87500Y295500D03*
X97800Y391800D03*
X99500Y370000D03*
X110500Y382500D03*
X107300D03*
X153500Y310500D03*
X201700Y327900D03*
X229582Y48918D03*
X225000Y396000D03*
X250222Y76300D03*
X247022D03*
X264339Y35300D03*
Y38500D03*
X269907Y76300D03*
X266707D03*
X280087Y35300D03*
Y38500D03*
X285055Y76300D03*
X281855D03*
X295835Y35300D03*
Y38500D03*
Y44900D03*
Y48100D03*
X306500Y169500D03*
X314763Y85237D03*
X312500Y87500D03*
X322710Y190299D03*
X323500Y263000D03*
X324000Y301000D03*
X325910Y190299D03*
X338500Y213500D03*
X330500Y265000D03*
X337500D03*
X332000Y301500D03*
X337000Y344000D03*
X345301Y193099D03*
Y189899D03*
X358000Y261500D03*
X344500Y265000D03*
X370500Y84000D03*
X365700Y92000D03*
X362500D03*
X374600Y178200D03*
X365101Y191559D03*
Y188359D03*
X375000Y210000D03*
X365500Y279500D03*
X369000Y413500D03*
X374500Y418500D03*
X391130Y146942D03*
Y135130D03*
Y162690D03*
Y154816D03*
Y170564D03*
Y182374D03*
Y186311D03*
X385500Y196154D03*
X387193Y186311D03*
X380000Y210000D03*
X391130Y209933D03*
X387193D03*
X394000Y223500D03*
X383000Y232500D03*
X390000D03*
X395000Y382000D03*
X395067Y143005D03*
Y131193D03*
X406879Y135130D03*
X410816D03*
X406879Y139067D03*
X402942D03*
X410811Y131188D03*
X406874D03*
X399000Y135125D03*
Y131188D03*
X395067Y135130D03*
X410816Y143005D03*
Y139067D03*
X406879Y143005D03*
X395067Y158753D03*
X399005Y150879D03*
X402942Y158753D03*
X406879Y162690D03*
Y154816D03*
Y158753D03*
X410816Y170564D03*
X399005Y166627D03*
X402942Y178437D03*
X406879D03*
X395067Y182374D03*
X399005Y186311D03*
Y190248D03*
X402942D03*
X406879Y182374D03*
Y186311D03*
Y194185D03*
X395067Y186311D03*
Y190248D03*
X402942Y182374D03*
X399005Y198122D03*
X395067D03*
X410816Y182374D03*
Y190248D03*
Y198122D03*
X402942Y186311D03*
Y194185D03*
X399005D03*
X402942Y198122D03*
X410816Y194185D03*
X406879Y190248D03*
X395067Y213870D03*
X410816Y205996D03*
X399005Y202059D03*
X395067D03*
X402942Y205996D03*
X399005D03*
X406879Y202059D03*
X410816Y209933D03*
Y202059D03*
X399005Y209933D03*
X395067D03*
X406879Y205996D03*
Y209933D03*
X402942Y202059D03*
X395067Y205996D03*
X406879Y213870D03*
Y217807D03*
X408000Y327000D03*
X420500Y82000D03*
X429000Y123500D03*
X422000D03*
X418500Y117000D03*
X415000Y123500D03*
X418690Y139067D03*
X422627Y135130D03*
X418690D03*
X414753D03*
X422627Y131193D03*
X418690D03*
X426564Y146942D03*
Y143005D03*
Y131193D03*
Y139067D03*
X422627D03*
Y143005D03*
X418690D03*
X414753D03*
Y139067D03*
X418690Y146942D03*
X414753D03*
X418690Y154816D03*
Y162690D03*
X414753Y158753D03*
X422627D03*
X426564Y154816D03*
X414753Y150879D03*
X422627D03*
X418690D03*
X426564D03*
Y178437D03*
X418690Y170564D03*
X414753Y166627D03*
X426564Y170564D03*
X414753Y178437D03*
X422627Y166627D03*
Y178437D03*
X414753Y194185D03*
X426564Y198122D03*
X418690Y182374D03*
X426564Y186311D03*
Y190248D03*
X418690Y198122D03*
X422627Y194185D03*
Y186311D03*
Y182374D03*
X426564D03*
X414753Y190248D03*
X418690D03*
Y186311D03*
X414753D03*
Y182374D03*
Y198122D03*
X426564Y194185D03*
X422627Y198122D03*
X418690Y194185D03*
X422627Y209933D03*
X418690Y205996D03*
X414753D03*
Y209933D03*
X418690Y213870D03*
X414753Y202059D03*
X426564D03*
Y205996D03*
Y209933D03*
X422627Y202059D03*
Y205996D03*
X418690Y209933D03*
X425400Y229600D03*
X420500Y229500D03*
X414900Y229800D03*
X423000Y235400D03*
X416100D03*
X429000Y274000D03*
X434437Y143005D03*
X438374Y131193D03*
X446248Y146942D03*
X442311Y143005D03*
Y146942D03*
X438374Y135130D03*
X434437Y146942D03*
X438374D03*
X446248Y139067D03*
X445939Y135439D03*
X438374Y143005D03*
Y139067D03*
X434437D03*
Y135130D03*
Y131193D03*
Y158753D03*
X442311D03*
X438374Y154816D03*
X446248D03*
Y162690D03*
X434437Y150879D03*
X442311D03*
X446248D03*
X438374Y178437D03*
Y170564D03*
X442311Y166627D03*
X434437Y178437D03*
X446248Y170564D03*
X442311Y178437D03*
X446248Y182374D03*
X438374Y190248D03*
X446248D03*
X434437Y186311D03*
Y190248D03*
Y194185D03*
Y182374D03*
X438374Y198122D03*
X442311Y190248D03*
Y194185D03*
X434437Y198122D03*
X446248D03*
X438374Y182374D03*
Y186311D03*
X446248Y194185D03*
X442311Y198122D03*
X438374Y209933D03*
Y205996D03*
Y202059D03*
X442311Y209933D03*
X438374Y213870D03*
X442311Y202059D03*
X434437D03*
Y213870D03*
X442311Y205996D03*
X446248D03*
Y202059D03*
X434437Y209933D03*
X438374Y217807D03*
X434437D03*
X430000Y386500D03*
X450185Y135130D03*
X461996Y139067D03*
X454122D03*
X458059D03*
X461996Y135130D03*
X454122D03*
X457844Y135345D03*
X449876Y131502D03*
X454122Y131193D03*
X458059Y146942D03*
X461996D03*
X450185D03*
X454122D03*
X458059Y143005D03*
X461996D03*
X450185Y139067D03*
X461996Y162690D03*
X458059Y158753D03*
X454122D03*
Y162690D03*
X450185Y158753D03*
X458059Y150879D03*
Y162690D03*
X454122Y150879D03*
X461996D03*
X454122Y154816D03*
X458059D03*
X461996D03*
X450185Y150879D03*
X458059Y178437D03*
X454122Y166627D03*
X450185D03*
Y178437D03*
X454122D03*
X461996Y170564D03*
Y178437D03*
X458060Y170564D03*
X461996Y166627D03*
X450185Y182374D03*
X458059Y190248D03*
X454122Y182374D03*
X461996D03*
X458059Y194185D03*
X461996Y186311D03*
X458059Y182374D03*
X454122Y194185D03*
X450185D03*
X454122Y190248D03*
X458059Y186311D03*
X454122Y198122D03*
X458059D03*
X461996Y190248D03*
Y198122D03*
Y194185D03*
X450185Y186311D03*
Y190248D03*
X454122Y205996D03*
X461996Y209933D03*
Y205996D03*
Y213870D03*
X458059Y202059D03*
Y205996D03*
X454122Y209933D03*
X458059D03*
X450185D03*
Y213870D03*
X454122D03*
X450185Y202059D03*
X454122D03*
X450185Y205996D03*
X454122Y217807D03*
X450185D03*
X461996D03*
X458059D03*
X479500Y92500D03*
X466500Y110400D03*
X471200Y115700D03*
X481600Y125800D03*
X476800Y120700D03*
X473807Y143005D03*
X465933Y139067D03*
X469870D03*
Y131193D03*
X473807D03*
X465933Y135130D03*
Y143005D03*
X469870D03*
X473807Y154816D03*
X465933Y162690D03*
X473807Y150879D03*
X465933Y154816D03*
X469870D03*
X475000Y163000D03*
X465933Y158753D03*
Y150879D03*
X469870D03*
X465933Y166627D03*
Y170564D03*
Y178437D03*
X469870Y166627D03*
Y170564D03*
X473807D03*
Y178437D03*
X465933Y194185D03*
X473807Y186311D03*
X469870Y198122D03*
X465933Y186311D03*
X469870Y190248D03*
X473807Y182374D03*
X469870D03*
X465933D03*
X469870Y186311D03*
X473807Y190248D03*
X469870Y194185D03*
X465933Y198122D03*
X482000Y212500D03*
X465933Y209933D03*
X469870Y213870D03*
Y209933D03*
X465933Y202059D03*
Y205996D03*
X473807Y213870D03*
X469870Y205996D03*
X473807Y209933D03*
Y217807D03*
X467000Y355500D03*
X482800Y110300D03*
X483000Y133000D03*
X485000Y154000D03*
X497500Y148500D03*
X491000Y154000D03*
X491500Y148500D03*
X497000Y154000D03*
X483100Y272800D03*
X503000Y155000D03*
X503500Y149000D03*
X534500Y253600D03*
X530000Y406500D03*
X544500Y79500D03*
X541000Y96000D03*
X540600Y234600D03*
X558000Y161500D03*
X566000Y347000D03*
X560000Y401000D03*
X580000Y104800D03*
X576500Y98000D03*
X576000Y246500D03*
X571800Y396500D03*
X587000Y184000D03*
X595500Y239000D03*
X619961Y224474D03*
Y227674D03*
G54D19*
X26378Y340080D03*
X28150Y343150D03*
X29922Y340080D03*
X33466D03*
X37010D03*
X40554D03*
X42326Y343150D03*
X38782D03*
X35238D03*
X31694D03*
G54D28*
X605315Y334449D03*
Y350984D03*
Y367519D03*
G54D24*
X126067Y184043D03*
X286067Y104043D03*
G54D31*
X640952Y201181D03*
Y220867D03*
G54D26*
X255906Y309646D03*
Y412008D03*
X494094Y309646D03*
Y412008D03*
G54D11*
X6039Y61260D03*
Y81260D03*
Y118346D03*
Y138346D03*
Y175433D03*
Y195433D03*
Y232520D03*
Y252520D03*
X26039Y61260D03*
Y81260D03*
Y118346D03*
Y138346D03*
Y175433D03*
Y195433D03*
Y232520D03*
Y252520D03*
G54D30*
X651582Y197244D03*
Y224804D03*
G54D23*
X126067Y104043D03*
Y264043D03*
X253967Y93443D03*
X265967D03*
X277867D03*
X286067Y264043D03*
G54D13*
X29528Y36811D03*
Y373031D03*
X640039Y65354D03*
Y417835D03*
G54D25*
X143567Y106043D03*
X146067Y268043D03*
X268567Y112143D03*
Y255943D03*
G54D29*
X634055Y334449D03*
Y367519D03*
G54D18*
X22834Y340080D03*
X24606Y343150D03*
X44098Y340080D03*
X45870Y343150D03*
G54D27*
X588779Y334449D03*
Y350984D03*
Y367519D03*
%LPC*%
G75*
G54D10*
X8878Y21717D03*
X4878D03*
X4000Y25619D03*
Y29619D03*
Y33619D03*
Y37619D03*
Y41619D03*
Y45619D03*
Y49619D03*
Y281619D03*
Y285619D03*
Y289619D03*
Y293619D03*
Y297619D03*
Y301619D03*
Y305619D03*
Y309619D03*
Y313619D03*
Y337619D03*
Y341619D03*
Y345619D03*
Y349619D03*
Y353619D03*
Y357619D03*
Y361619D03*
Y365619D03*
Y369619D03*
Y373619D03*
Y377619D03*
Y381619D03*
Y385619D03*
Y389619D03*
Y393619D03*
Y397619D03*
Y401619D03*
Y405619D03*
Y409619D03*
Y413619D03*
Y417619D03*
Y421619D03*
Y425619D03*
Y429619D03*
X4413Y433598D03*
X8413D03*
X24878Y21717D03*
X20878D03*
X16878D03*
X12878D03*
X12413Y433598D03*
X16413D03*
X20413D03*
X24413D03*
X28413D03*
X44878Y21717D03*
X40878D03*
X36878D03*
X32878D03*
X28878D03*
X32413Y433598D03*
X36413D03*
X40413D03*
X44413D03*
X55055Y25073D03*
X52878Y21717D03*
X48878D03*
X55055Y41073D03*
Y37073D03*
Y33073D03*
Y29073D03*
X61463Y54048D03*
X57859Y52313D03*
X55558Y49041D03*
X55055Y45073D03*
X48413Y433598D03*
X52413D03*
X56413D03*
X60413D03*
X77460Y54197D03*
X73460D03*
X69460D03*
X65460D03*
X79248Y266100D03*
X67000Y283100D03*
X76700Y357500D03*
X67100D03*
X68413Y433598D03*
X72413D03*
X76413D03*
X80413D03*
X64413D03*
X97460Y54197D03*
X93460D03*
X89460D03*
X85460D03*
X81460D03*
X86800Y230000D03*
X85600Y263700D03*
X85800Y287452D03*
X84413Y433598D03*
X88413D03*
X92413D03*
X96413D03*
X113460Y54197D03*
X109460D03*
X105460D03*
X101460D03*
X113700Y382500D03*
X104100D03*
X104413Y433598D03*
X108413D03*
X112413D03*
X100413D03*
X132920Y51926D03*
X129450Y53917D03*
X125460Y54197D03*
X121460D03*
X117460D03*
X116413Y433598D03*
X120413D03*
X124413D03*
X128413D03*
X132413D03*
X135299Y24509D03*
X150163Y21717D03*
X146163D03*
X142163D03*
X138163D03*
X135299Y28509D03*
Y32509D03*
Y36509D03*
Y40509D03*
Y44509D03*
X134977Y48496D03*
X144000Y62500D03*
X138500Y75000D03*
X140413Y433598D03*
X144413D03*
X148413D03*
X136413D03*
X158163Y21717D03*
X154163D03*
X158795Y25667D03*
Y41667D03*
Y37667D03*
Y33667D03*
Y29667D03*
X160736Y49309D03*
X159112Y45654D03*
X163543Y52159D03*
X151840Y79935D03*
X167100Y405600D03*
X152413Y433598D03*
X156413D03*
X160413D03*
X164413D03*
X180341Y47225D03*
X178196Y50601D03*
X168413Y433598D03*
X172413D03*
X176413D03*
X180413D03*
X184413D03*
X191535Y28900D03*
X201950Y29050D03*
X200413Y433598D03*
X188413D03*
X192413D03*
X196413D03*
X208300Y289500D03*
X217300D03*
X209660Y331500D03*
X204413Y433598D03*
X208413D03*
X212413D03*
X216413D03*
X220413D03*
X232700Y29100D03*
X221800Y289500D03*
X224413Y433598D03*
X228413D03*
X232413D03*
X236413D03*
X254527Y28900D03*
X244619D03*
X240508Y76300D03*
Y66700D03*
X243822Y76300D03*
X253422D03*
X240413Y433598D03*
X244413D03*
X248413D03*
X252413D03*
X264339Y32100D03*
X264304Y28900D03*
X272309D03*
X264339Y41700D03*
X263507Y76300D03*
X256413Y433598D03*
X260413D03*
X264413D03*
X268413D03*
X272413D03*
X280087Y41700D03*
Y32100D03*
X280052Y28900D03*
X288057D03*
X288255Y76300D03*
X273107D03*
X278655D03*
X284500Y181100D03*
X277000Y198700D03*
X286600D03*
X284500Y190700D03*
X286151Y329500D03*
X288413Y433598D03*
X284413D03*
X280413D03*
X276413D03*
X295835Y41700D03*
Y32100D03*
X295800Y28900D03*
X298726Y43529D03*
Y49471D03*
X304413Y433598D03*
X300413D03*
X296413D03*
X292413D03*
X307708Y28900D03*
X321402Y54197D03*
X317402D03*
X310237Y89763D03*
X317025Y82975D03*
X319510Y190299D03*
X322200Y325000D03*
X310600Y330500D03*
X324413Y433598D03*
X320413D03*
X316413D03*
X312413D03*
X308413D03*
X329402Y54197D03*
X325402D03*
X337402D03*
X341402D03*
X333402D03*
X338599Y108500D03*
X337500Y113000D03*
Y122600D03*
X329110Y190299D03*
X340413Y433598D03*
X336413D03*
X332413D03*
X328413D03*
X345402Y54197D03*
X349402D03*
X353402D03*
X357402D03*
X359300Y92000D03*
X348199Y108500D03*
X348264Y104707D03*
X357864D03*
X345301Y196299D03*
Y186699D03*
X354850Y276100D03*
X354800Y289800D03*
X355000Y332500D03*
X356413Y433598D03*
X352413D03*
X348413D03*
X344413D03*
X369402Y54197D03*
X373402D03*
X377402D03*
X361402D03*
X365402D03*
X373500Y78000D03*
X368900Y92000D03*
X373500Y94000D03*
X365101Y194759D03*
Y185159D03*
X376413Y433598D03*
X372413D03*
X368413D03*
X364413D03*
X360413D03*
X381402Y54197D03*
X385402D03*
X389402D03*
X393402D03*
X379500Y72500D03*
X380500Y77400D03*
X390000Y100500D03*
X387193Y135130D03*
X391130Y139067D03*
X387193D03*
Y146942D03*
Y154816D03*
Y162690D03*
Y170564D03*
X391130Y178437D03*
X387193D03*
X391130Y205996D03*
X387193Y217807D03*
X392413Y433598D03*
X388413D03*
X384413D03*
X380413D03*
X397402Y54197D03*
X401402D03*
X405402D03*
X409402D03*
X396400Y100500D03*
X409200D03*
X398450Y116099D03*
X408050D03*
X395067Y139067D03*
X399005D03*
Y143005D03*
X402942D03*
Y146942D03*
X406879D03*
X410816D03*
X395067Y150879D03*
X402942Y154816D03*
X399005Y158753D03*
X410816D03*
X402942Y162690D03*
X410816D03*
Y150879D03*
Y154816D03*
X395067Y166627D03*
X410816D03*
X402942Y170564D03*
X406879D03*
X395067Y178437D03*
X399005D03*
X410816D03*
X406879Y198122D03*
X399005Y182374D03*
X410816Y186311D03*
X395067Y194185D03*
X402942Y209933D03*
X408413Y433598D03*
X404413D03*
X400413D03*
X396413D03*
X417402Y54197D03*
X421402D03*
X425402D03*
X429402D03*
X413402D03*
X413622Y75000D03*
X414753Y131193D03*
X422627Y146942D03*
X426564Y135130D03*
X414753Y162690D03*
Y154816D03*
X418690Y158753D03*
X422627Y162690D03*
Y154816D03*
X426564Y162690D03*
Y158753D03*
X418690Y166627D03*
X414753Y170564D03*
X422627D03*
X418690Y178437D03*
X426564Y166627D03*
X422627Y190248D03*
X414753Y213870D03*
X418690Y202059D03*
X426564Y217807D03*
X428413Y433598D03*
X424413D03*
X420413D03*
X416413D03*
X412413D03*
X433402Y54197D03*
X437402D03*
X441402D03*
X445402D03*
X444050Y116599D03*
X434450D03*
X442311Y139067D03*
X446248Y158753D03*
X442311Y162690D03*
X434437D03*
Y154816D03*
X438374Y162690D03*
Y150879D03*
Y158753D03*
X442311Y154816D03*
X438374Y166627D03*
X446248D03*
X434437Y170564D03*
X442311D03*
X446248Y178437D03*
X434437Y166627D03*
X442311Y182374D03*
X438374Y194185D03*
X434437Y205996D03*
X446248Y209933D03*
X446500Y289500D03*
X439500Y337892D03*
X443000Y401500D03*
Y396500D03*
X444000Y416500D03*
X444413Y433598D03*
X440413D03*
X436413D03*
X432413D03*
X449402Y54197D03*
X453402D03*
X457402D03*
X461402D03*
X450930Y122167D03*
X460530D03*
X454122Y143005D03*
X457844Y131408D03*
X450185Y154816D03*
X461996Y158753D03*
X450185Y162690D03*
X458059Y166627D03*
X450185Y170564D03*
X454123D03*
X454122Y186311D03*
X450185Y198122D03*
X461996Y202059D03*
X458059Y213870D03*
X464413Y433598D03*
X460413D03*
X456413D03*
X452413D03*
X448413D03*
X465402Y54197D03*
X469402D03*
X473402D03*
X477402D03*
X481402D03*
X465933Y146942D03*
X469870Y135130D03*
Y178437D03*
X473807Y166627D03*
X465933Y190248D03*
X473807Y205996D03*
X469870Y217807D03*
X480413Y433598D03*
X476413D03*
X472413D03*
X468413D03*
X485402Y54197D03*
X489402D03*
X493402D03*
X497402D03*
X496413Y433598D03*
X492413D03*
X488413D03*
X484413D03*
X501402Y54197D03*
X505402D03*
X509402D03*
X513402D03*
X516413Y433598D03*
X512413D03*
X508413D03*
X504413D03*
X500413D03*
X517402Y54197D03*
X521402D03*
X525402D03*
X529402D03*
X533402D03*
X532413Y433598D03*
X528413D03*
X524413D03*
X520413D03*
X537402Y54197D03*
X541402D03*
X545402D03*
X549402D03*
X548413Y433598D03*
X544413D03*
X540413D03*
X536413D03*
X553402Y54197D03*
X557402D03*
X561402D03*
X565402D03*
X566600Y212900D03*
X568413Y433598D03*
X564413D03*
X560413D03*
X556413D03*
X552413D03*
X569402Y54197D03*
X573402D03*
X577402D03*
X581402D03*
X585402D03*
X584413Y433598D03*
X580413D03*
X576413D03*
X572413D03*
X589402Y54197D03*
X593402D03*
X597402D03*
X601402D03*
X600413Y433598D03*
X596413D03*
X592413D03*
X588413D03*
X605402Y54197D03*
X609402D03*
X613402D03*
X617402D03*
X621402D03*
X619961Y230874D03*
Y221274D03*
X620413Y433598D03*
X616413D03*
X612413D03*
X608413D03*
X604413D03*
X625402Y54197D03*
X629402D03*
X636413Y433598D03*
X632413D03*
X628413D03*
X624413D03*
X649402Y54197D03*
X653402D03*
X656039Y57205D03*
Y61205D03*
Y65205D03*
Y69205D03*
Y73205D03*
Y77205D03*
Y81205D03*
Y85205D03*
Y89205D03*
Y93205D03*
Y97205D03*
Y101205D03*
Y105205D03*
Y109205D03*
Y113205D03*
Y117205D03*
Y121205D03*
Y125205D03*
Y129205D03*
Y145205D03*
Y133205D03*
Y137205D03*
Y141205D03*
Y149205D03*
Y153205D03*
Y157205D03*
Y161205D03*
Y165205D03*
Y169205D03*
Y173205D03*
Y177205D03*
Y181205D03*
Y235585D03*
Y311909D03*
Y315909D03*
Y319909D03*
Y323909D03*
Y327909D03*
Y331909D03*
Y335909D03*
Y339909D03*
Y343909D03*
Y347909D03*
Y351909D03*
Y355909D03*
Y359909D03*
Y363909D03*
Y367909D03*
Y371909D03*
Y375909D03*
Y379909D03*
Y383909D03*
Y387909D03*
Y391909D03*
Y395909D03*
Y399909D03*
Y403909D03*
Y407909D03*
Y411909D03*
Y415909D03*
Y419909D03*
Y423909D03*
Y427909D03*
Y431909D03*
X652413Y433598D03*
X648413D03*
X644413D03*
X640413D03*
G54D32*
G01X136000Y-65500D02*
Y-158000D01*
X506000D01*
Y-65500D01*
X136000D01*
G01X316000D02*
Y-158000D01*
G54D14*
X19878Y36811D03*
X22704Y29987D03*
Y43635D03*
X19878Y373031D03*
X22704Y366207D03*
Y379855D03*
X29528Y27161D03*
X36352Y29987D03*
X39178Y36811D03*
X36352Y43635D03*
X29528Y46461D03*
Y363381D03*
X36352Y366207D03*
X39178Y373031D03*
X36352Y379855D03*
X29528Y382681D03*
X633215Y58530D03*
Y72178D03*
X630389Y65354D03*
X633215Y424659D03*
X630389Y417835D03*
X633215Y411011D03*
X640039Y55704D03*
X646863Y58530D03*
X649689Y65354D03*
X646863Y72178D03*
X640039Y75004D03*
Y408185D03*
X646863Y411011D03*
X649689Y417835D03*
X646863Y424659D03*
X640039Y427485D03*
G54D33*
G01X329433Y-125500D02*
Y-133000D01*
X333167D01*
G01X340480D02*
Y-128000D01*
G01Y-128875D02*
X340107Y-128375D01*
X339547Y-128125D01*
X338893Y-128000D01*
X338240Y-128250D01*
X337680Y-128750D01*
X337307Y-129500D01*
X337120Y-130500D01*
X337307Y-131500D01*
X337680Y-132250D01*
X338240Y-132750D01*
X338893Y-133000D01*
X339547Y-132875D01*
X340107Y-132500D01*
X340480Y-132000D01*
G01X344340Y-135250D02*
X344900Y-135500D01*
X345647Y-135250D01*
X346113Y-134750D01*
X346487Y-134125D01*
X347047Y-132125D01*
X348260Y-128000D01*
G01X345273D02*
X347047Y-132125D01*
G01X352400Y-129625D02*
X355387D01*
X355107Y-128750D01*
X354640Y-128250D01*
X353987Y-128000D01*
X353333Y-128125D01*
X352773Y-128500D01*
X352400Y-129375D01*
X352213Y-130125D01*
Y-130875D01*
X352400Y-131625D01*
X352867Y-132375D01*
X353427Y-132875D01*
X354080Y-133000D01*
X354733Y-132750D01*
X355387Y-132000D01*
G01X359993Y-133000D02*
Y-128000D01*
G01Y-129000D02*
X360460Y-128500D01*
X360927Y-128125D01*
X361580Y-128000D01*
X362047Y-128125D01*
X362607Y-128500D01*
G01X368800Y-133250D02*
X368613Y-133125D01*
Y-132875D01*
X368800Y-132750D01*
X368987Y-132875D01*
Y-133125D01*
X368800Y-133250D01*
G01Y-129875D02*
X368613Y-129750D01*
Y-129500D01*
X368800Y-129375D01*
X368987Y-129500D01*
Y-129750D01*
X368800Y-129875D01*
G01X336747Y-120500D02*
Y-113000D01*
X338613D01*
X339360Y-113375D01*
X339920Y-113875D01*
X340387Y-114625D01*
X340760Y-115500D01*
X340853Y-116750D01*
X340760Y-118000D01*
X340387Y-118875D01*
X339920Y-119625D01*
X339360Y-120125D01*
X338613Y-120500D01*
X336747D01*
G01X347980D02*
Y-115500D01*
G01Y-116375D02*
X347607Y-115875D01*
X347047Y-115625D01*
X346393Y-115500D01*
X345740Y-115750D01*
X345180Y-116250D01*
X344807Y-117000D01*
X344620Y-118000D01*
X344807Y-119000D01*
X345180Y-119750D01*
X345740Y-120250D01*
X346393Y-120500D01*
X347047Y-120375D01*
X347607Y-120000D01*
X347980Y-119500D01*
G01X353800Y-113000D02*
Y-120500D01*
G01X352493Y-115500D02*
X355107D01*
G01X359900Y-117125D02*
X362887D01*
X362607Y-116250D01*
X362140Y-115750D01*
X361487Y-115500D01*
X360833Y-115625D01*
X360273Y-116000D01*
X359900Y-116875D01*
X359713Y-117625D01*
Y-118375D01*
X359900Y-119125D01*
X360367Y-119875D01*
X360927Y-120375D01*
X361580Y-120500D01*
X362233Y-120250D01*
X362887Y-119500D01*
G01X368800Y-120750D02*
X368613Y-120625D01*
Y-120375D01*
X368800Y-120250D01*
X368987Y-120375D01*
Y-120625D01*
X368800Y-120750D01*
G01Y-117375D02*
X368613Y-117250D01*
Y-117000D01*
X368800Y-116875D01*
X368987Y-117000D01*
Y-117250D01*
X368800Y-117375D01*
G01X382027Y-114250D02*
X382587Y-113500D01*
X383240Y-113125D01*
X383987Y-113000D01*
X384920Y-113250D01*
X385573Y-113875D01*
X385760Y-114625D01*
X385667Y-115375D01*
X385293Y-116000D01*
X383427Y-117250D01*
X382587Y-118125D01*
X382027Y-119375D01*
X381840Y-120500D01*
X385760D01*
G01X391300Y-113000D02*
X390553Y-113250D01*
X389993Y-113875D01*
X389620Y-114625D01*
X389340Y-115625D01*
X389247Y-116750D01*
X389340Y-117875D01*
X389620Y-118875D01*
X389993Y-119625D01*
X390553Y-120250D01*
X391300Y-120500D01*
X392047Y-120250D01*
X392607Y-119625D01*
X392980Y-118875D01*
X393260Y-117875D01*
X393353Y-116750D01*
X393260Y-115625D01*
X392980Y-114625D01*
X392607Y-113875D01*
X392047Y-113250D01*
X391300Y-113000D01*
G01X397027Y-114250D02*
X397587Y-113500D01*
X398240Y-113125D01*
X398987Y-113000D01*
X399920Y-113250D01*
X400573Y-113875D01*
X400760Y-114625D01*
X400667Y-115375D01*
X400293Y-116000D01*
X398427Y-117250D01*
X397587Y-118125D01*
X397027Y-119375D01*
X396840Y-120500D01*
X400760D01*
G01X404527Y-114250D02*
X405087Y-113500D01*
X405740Y-113125D01*
X406487Y-113000D01*
X407420Y-113250D01*
X408073Y-113875D01*
X408260Y-114625D01*
X408167Y-115375D01*
X407793Y-116000D01*
X405927Y-117250D01*
X405087Y-118125D01*
X404527Y-119375D01*
X404340Y-120500D01*
X408260D01*
G01X412587Y-118000D02*
X415013D01*
G01X421300Y-113000D02*
X420553Y-113250D01*
X419993Y-113875D01*
X419620Y-114625D01*
X419340Y-115625D01*
X419247Y-116750D01*
X419340Y-117875D01*
X419620Y-118875D01*
X419993Y-119625D01*
X420553Y-120250D01*
X421300Y-120500D01*
X422047Y-120250D01*
X422607Y-119625D01*
X422980Y-118875D01*
X423260Y-117875D01*
X423353Y-116750D01*
X423260Y-115625D01*
X422980Y-114625D01*
X422607Y-113875D01*
X422047Y-113250D01*
X421300Y-113000D01*
G01X427027Y-114250D02*
X427587Y-113500D01*
X428240Y-113125D01*
X428987Y-113000D01*
X429920Y-113250D01*
X430573Y-113875D01*
X430760Y-114625D01*
X430667Y-115375D01*
X430293Y-116000D01*
X428427Y-117250D01*
X427587Y-118125D01*
X427027Y-119375D01*
X426840Y-120500D01*
X430760D01*
G01X435087Y-118000D02*
X437513D01*
G01X442027Y-114250D02*
X442587Y-113500D01*
X443240Y-113125D01*
X443987Y-113000D01*
X444920Y-113250D01*
X445573Y-113875D01*
X445760Y-114625D01*
X445667Y-115375D01*
X445293Y-116000D01*
X443427Y-117250D01*
X442587Y-118125D01*
X442027Y-119375D01*
X441840Y-120500D01*
X445760D01*
G01X449247Y-119375D02*
X449807Y-120000D01*
X450460Y-120375D01*
X451300Y-120500D01*
X452140Y-120250D01*
X452793Y-119750D01*
X453260Y-118875D01*
X453353Y-117875D01*
X453167Y-116875D01*
X452700Y-116250D01*
X452047Y-115750D01*
X451393Y-115625D01*
X450740Y-115750D01*
X449900Y-116250D01*
X450180Y-113000D01*
X452700D01*
G01X336933Y-108000D02*
Y-100500D01*
X339267D01*
X340013Y-100875D01*
X340480Y-101375D01*
X340667Y-102375D01*
X340480Y-103375D01*
X339920Y-104000D01*
X339267Y-104375D01*
X336933D01*
G01X339267D02*
X340667Y-108000D01*
G01X344900Y-104625D02*
X347887D01*
X347607Y-103750D01*
X347140Y-103250D01*
X346487Y-103000D01*
X345833Y-103125D01*
X345273Y-103500D01*
X344900Y-104375D01*
X344713Y-105125D01*
Y-105875D01*
X344900Y-106625D01*
X345367Y-107375D01*
X345927Y-107875D01*
X346580Y-108000D01*
X347233Y-107750D01*
X347887Y-107000D01*
G01X352120Y-103000D02*
X353800Y-108000D01*
X355480Y-103000D01*
G01X368800Y-108250D02*
X368613Y-108125D01*
Y-107875D01*
X368800Y-107750D01*
X368987Y-107875D01*
Y-108125D01*
X368800Y-108250D01*
G01Y-104875D02*
X368613Y-104750D01*
Y-104500D01*
X368800Y-104375D01*
X368987Y-104500D01*
Y-104750D01*
X368800Y-104875D01*
G01X383800Y-100500D02*
X383053Y-100750D01*
X382493Y-101375D01*
X382120Y-102125D01*
X381840Y-103125D01*
X381747Y-104250D01*
X381840Y-105375D01*
X382120Y-106375D01*
X382493Y-107125D01*
X383053Y-107750D01*
X383800Y-108000D01*
X384547Y-107750D01*
X385107Y-107125D01*
X385480Y-106375D01*
X385760Y-105375D01*
X385853Y-104250D01*
X385760Y-103125D01*
X385480Y-102125D01*
X385107Y-101375D01*
X384547Y-100750D01*
X383800Y-100500D01*
G01X391300Y-108000D02*
Y-100500D01*
X390180Y-102000D01*
G01Y-108000D02*
X392420D01*
G01X336933Y-95500D02*
Y-88000D01*
X339173D01*
X339920Y-88375D01*
X340480Y-89250D01*
X340667Y-90250D01*
X340480Y-91250D01*
X340013Y-92000D01*
X339173Y-92375D01*
X336933D01*
G01X344620Y-95750D02*
X347980Y-88000D01*
G01X351653Y-95500D02*
Y-88000D01*
X355947Y-95500D01*
Y-88000D01*
G01X368800Y-95750D02*
X368613Y-95625D01*
Y-95375D01*
X368800Y-95250D01*
X368987Y-95375D01*
Y-95625D01*
X368800Y-95750D01*
G01Y-92375D02*
X368613Y-92250D01*
Y-92000D01*
X368800Y-91875D01*
X368987Y-92000D01*
Y-92250D01*
X368800Y-92375D01*
G01X381933Y-95500D02*
Y-88000D01*
X384267D01*
X385013Y-88375D01*
X385480Y-88875D01*
X385667Y-89875D01*
X385480Y-90875D01*
X384920Y-91500D01*
X384267Y-91875D01*
X381933D01*
G01X384267D02*
X385667Y-95500D01*
G01X392420D02*
Y-88000D01*
X388967Y-93375D01*
X393633D01*
G01X398800Y-88000D02*
X398053Y-88250D01*
X397493Y-88875D01*
X397120Y-89625D01*
X396840Y-90625D01*
X396747Y-91750D01*
X396840Y-92875D01*
X397120Y-93875D01*
X397493Y-94625D01*
X398053Y-95250D01*
X398800Y-95500D01*
X399547Y-95250D01*
X400107Y-94625D01*
X400480Y-93875D01*
X400760Y-92875D01*
X400853Y-91750D01*
X400760Y-90625D01*
X400480Y-89625D01*
X400107Y-88875D01*
X399547Y-88250D01*
X398800Y-88000D01*
G01X406300D02*
X405553Y-88250D01*
X404993Y-88875D01*
X404620Y-89625D01*
X404340Y-90625D01*
X404247Y-91750D01*
X404340Y-92875D01*
X404620Y-93875D01*
X404993Y-94625D01*
X405553Y-95250D01*
X406300Y-95500D01*
X407047Y-95250D01*
X407607Y-94625D01*
X407980Y-93875D01*
X408260Y-92875D01*
X408353Y-91750D01*
X408260Y-90625D01*
X407980Y-89625D01*
X407607Y-88875D01*
X407047Y-88250D01*
X406300Y-88000D01*
G01X412027Y-92375D02*
X412680Y-91500D01*
X413240Y-91000D01*
X413987Y-90750D01*
X414640Y-91000D01*
X415107Y-91500D01*
X415480Y-92250D01*
X415573Y-93125D01*
X415480Y-93875D01*
X415107Y-94625D01*
X414547Y-95250D01*
X413893Y-95500D01*
X413147Y-95250D01*
X412493Y-94500D01*
X412120Y-93375D01*
X412027Y-92125D01*
X412213Y-90500D01*
X412493Y-89625D01*
X412960Y-88750D01*
X413613Y-88125D01*
X414267Y-88000D01*
X414920Y-88250D01*
X415387Y-88875D01*
G01X420087Y-93000D02*
X422513D01*
G01X429547Y-91500D02*
X429920Y-91125D01*
X430200Y-90500D01*
X430387Y-89625D01*
X430200Y-88875D01*
X429827Y-88375D01*
X429173Y-88000D01*
X426653D01*
Y-95500D01*
X429733D01*
X430387Y-95000D01*
X430760Y-94250D01*
X430947Y-93375D01*
X430760Y-92500D01*
X430200Y-91750D01*
X429547Y-91500D01*
X426653D01*
G01X436300Y-88000D02*
X435553Y-88250D01*
X434993Y-88875D01*
X434620Y-89625D01*
X434340Y-90625D01*
X434247Y-91750D01*
X434340Y-92875D01*
X434620Y-93875D01*
X434993Y-94625D01*
X435553Y-95250D01*
X436300Y-95500D01*
X437047Y-95250D01*
X437607Y-94625D01*
X437980Y-93875D01*
X438260Y-92875D01*
X438353Y-91750D01*
X438260Y-90625D01*
X437980Y-89625D01*
X437607Y-88875D01*
X437047Y-88250D01*
X436300Y-88000D01*
G01X443800D02*
X443053Y-88250D01*
X442493Y-88875D01*
X442120Y-89625D01*
X441840Y-90625D01*
X441747Y-91750D01*
X441840Y-92875D01*
X442120Y-93875D01*
X442493Y-94625D01*
X443053Y-95250D01*
X443800Y-95500D01*
X444547Y-95250D01*
X445107Y-94625D01*
X445480Y-93875D01*
X445760Y-92875D01*
X445853Y-91750D01*
X445760Y-90625D01*
X445480Y-89625D01*
X445107Y-88875D01*
X444547Y-88250D01*
X443800Y-88000D01*
G01X451300D02*
X450553Y-88250D01*
X449993Y-88875D01*
X449620Y-89625D01*
X449340Y-90625D01*
X449247Y-91750D01*
X449340Y-92875D01*
X449620Y-93875D01*
X449993Y-94625D01*
X450553Y-95250D01*
X451300Y-95500D01*
X452047Y-95250D01*
X452607Y-94625D01*
X452980Y-93875D01*
X453260Y-92875D01*
X453353Y-91750D01*
X453260Y-90625D01*
X452980Y-89625D01*
X452607Y-88875D01*
X452047Y-88250D01*
X451300Y-88000D01*
G01X458800Y-95500D02*
Y-88000D01*
X457680Y-89500D01*
G01Y-95500D02*
X459920D01*
G01X465087Y-93000D02*
X467513D01*
G01X473800Y-88000D02*
X473053Y-88250D01*
X472493Y-88875D01*
X472120Y-89625D01*
X471840Y-90625D01*
X471747Y-91750D01*
X471840Y-92875D01*
X472120Y-93875D01*
X472493Y-94625D01*
X473053Y-95250D01*
X473800Y-95500D01*
X474547Y-95250D01*
X475107Y-94625D01*
X475480Y-93875D01*
X475760Y-92875D01*
X475853Y-91750D01*
X475760Y-90625D01*
X475480Y-89625D01*
X475107Y-88875D01*
X474547Y-88250D01*
X473800Y-88000D01*
G01X479527Y-89250D02*
X480087Y-88500D01*
X480740Y-88125D01*
X481487Y-88000D01*
X482420Y-88250D01*
X483073Y-88875D01*
X483260Y-89625D01*
X483167Y-90375D01*
X482793Y-91000D01*
X480927Y-92250D01*
X480087Y-93125D01*
X479527Y-94375D01*
X479340Y-95500D01*
X483260D01*
G54D34*
G01X145964Y-110118D02*
G03I-634J0D01*
G01X149695D02*
G03I-1038J0D01*
G01X168013Y-137456D02*
G03I-634J0D01*
G01X155900Y-133655D02*
G03I-632J0D01*
G01X161735Y-128639D02*
G03I-1458J0D01*
G01X158530Y-131428D02*
G03I-1041J0D01*
G01X158461Y-119126D02*
G03I-1283J0D01*
G01X162690Y-117490D02*
G03I-1584J0D01*
G01X169809Y-121292D02*
G03I-2180J0D01*
G01X165531Y-125255D02*
G03I-1869J0D01*
G01X167813Y-115513D02*
G03I-1971J0D01*
G01X154775Y-120500D02*
G03I-892J0D01*
G01X162681Y-102774D02*
G03I-1584J0D01*
G01X158451Y-101149D02*
G03I-1283J0D01*
G01X159258Y-110118D02*
G03I-1868J0D01*
G01X169812Y-98951D02*
G03I-2180J0D01*
G01X167802Y-104739D02*
G03I-1971J0D01*
G01X165183Y-110118D02*
G03I-2180J0D01*
G01X171881D02*
G03I-2642J0D01*
G01X152135Y-98681D02*
G03I-632J0D01*
G01X154064Y-110118D02*
G03I-1460J0D01*
G01X154764Y-99775D02*
G03I-892J0D01*
G01X158530Y-88809D02*
G03I-1041J0D01*
G01X161742Y-91601D02*
G03I-1458J0D01*
G01X165531Y-94981D02*
G03I-1869J0D01*
G01X171080Y-131739D02*
G03I-1282J0D01*
G01X169322Y-135033D02*
G03I-892J0D01*
G01X180669Y-131528D02*
G03I-1870J0D01*
G01X180255Y-136311D02*
G03I-1456J0D01*
G01X179841Y-140261D02*
G03I-1042J0D01*
G01X179433Y-143587D02*
G03I-634J0D01*
G01X181439Y-119680D02*
G03I-2640J0D01*
G01X175373Y-123081D02*
G03I-1968J0D01*
G01X173018Y-127816D02*
G03I-1584J0D01*
G01X174681Y-116876D02*
G03I-2640J0D01*
G01X180979Y-125917D02*
G03I-2180J0D01*
G01X186177Y-123075D02*
G03I-1971J0D01*
G01X188199Y-116876D02*
G03I-2640J0D01*
G01X175452Y-97124D02*
G03I-1968J0D01*
G01X186225Y-97178D02*
G03I-1971J0D01*
G01X181439Y-100556D02*
G03I-2640J0D01*
G01X174681Y-103361D02*
G03I-2640J0D01*
G01X188199D02*
G03I-2640J0D01*
G01X179841Y-79975D02*
G03I-1042J0D01*
G01X171217Y-88444D02*
G03I-1282J0D01*
G01X173123Y-92378D02*
G03I-1584J0D01*
G01X180255Y-83924D02*
G03I-1456J0D01*
G01X180669Y-88708D02*
G03I-1870J0D01*
G01X180979Y-94320D02*
G03I-2180J0D01*
G01X179433Y-76648D02*
G03I-634J0D01*
G01X191096Y-134658D02*
G03I-892J0D01*
G01X192135Y-136781D02*
G03I-631J0D01*
G01X198775Y-128635D02*
G03I-1458J0D01*
G01X195808Y-125255D02*
G03I-1869J0D01*
G01X200547Y-113952D02*
G03X203345Y-117196I7247J3422D01*
G01X192148Y-121285D02*
G03I-2180J0D01*
G01X187928Y-127802D02*
G03I-1584J0D01*
G01X189667Y-131511D02*
G03I-1283J0D01*
G01X200699Y-105836D02*
G03X200547Y-113953I8974J-4228D01*
G01X208284Y-101612D02*
G03X200698Y-105835I-219J-8531D01*
G01X192148Y-98951D02*
G03I-2180J0D01*
G01X191108Y-82727D02*
G03I-634J0D01*
G01X190184Y-85250D02*
G03I-893J0D01*
G01X195808Y-94981D02*
G03I-1869J0D01*
G01X187839Y-92457D02*
G03I-1584J0D01*
G01X189190Y-88538D02*
G03I-1283J0D01*
G01X214259Y-115661D02*
G03X213314Y-114453I-714J415D01*
G01X202049Y-108260D02*
G03X205722Y-116181I7039J-1548D01*
G01X218075Y-112869D02*
G03X219083Y-115752I4343J-99D01*
G01X208854Y-116658D02*
G03X213313Y-114452I-2485J10632D01*
G01X208470Y-118462D02*
G03X214261Y-115663I-1122J9711D01*
G01X203346Y-117195D02*
G03X208470Y-118461I4545J7394D01*
G01X205721Y-116179D02*
G03X208853Y-116659I2561J6250D01*
G01X215903Y-114020D02*
G03X219079Y-118061I6190J1597D01*
G01X215904Y-114020D02*
Y-111835D01*
G01X227413Y-112869D02*
X218074D01*
G01X214175Y-103951D02*
G03X208283Y-101613I-6403J-7542D01*
G01X213150Y-105147D02*
G03X214175Y-103951I410J686D01*
G01X213152Y-105146D02*
G03X208030Y-103430I-5122J-6786D01*
G01X208029Y-103429D02*
G03X202049Y-108259I-48J-6058D01*
G01X225189Y-111399D02*
G03X218071I-3559J159D01*
G01X218070Y-111418D02*
Y-111399D01*
G01X225188Y-111418D02*
X218070D01*
G01X227412Y-111835D02*
G03X215906I-5753J223D01*
G01X230059Y-117625D02*
Y-102034D01*
G01X230060Y-117626D02*
G03X232080I1010J239D01*
G01X226590Y-116472D02*
G03X225311Y-115210I-817J451D01*
G01X234673Y-114020D02*
G03X237849Y-118061I6190J1597D01*
G01X232081Y-102041D02*
Y-117625D01*
G01X219083Y-115753D02*
G03X225311Y-115211I2844J3371D01*
G01X219079Y-118060D02*
G03X226591Y-116473I2662J5972D01*
G01X227413Y-111835D02*
Y-112869D01*
G01X232080Y-102041D02*
G03X230060Y-102034I-1011J-236D01*
G01X225188Y-111399D02*
Y-111418D01*
G01X234675Y-114020D02*
Y-111835D01*
G01X246181D02*
G03X234675I-5753J223D01*
G01X252849Y-116771D02*
G03X254892Y-115895I-74J2994D01*
G01X236844Y-112869D02*
G03X237852Y-115752I4343J-99D01*
G01X237848Y-118060D02*
G03X245360Y-116473I2662J5972D01*
G01X245358Y-116472D02*
G03X244079Y-115210I-817J451D01*
G01X237852Y-115753D02*
G03X244080Y-115211I2844J3371D01*
G01X249566Y-115529D02*
G03X252307Y-116760I2985J2980D01*
G01Y-116761D02*
G03X252849Y-116772I366J4691D01*
G01X250282Y-118087D02*
G03X254318Y-118340I2605J9244D01*
G01X247897Y-116444D02*
G03X250283Y-118086I3752J2898D01*
G01X249568Y-115529D02*
G03X247898Y-116443I-748J-616D01*
G01X255608Y-108618D02*
G03X253612Y-107689I-3116J-4086D01*
G01X246181Y-111835D02*
Y-112869D01*
G01D02*
X236844D01*
G01X255002Y-114328D02*
G03X252723Y-112986I-3540J-3405D01*
G01X249955Y-112030D02*
G03X252723Y-112985I8208J19302D01*
G01X243957Y-111399D02*
Y-111418D01*
G01X243958Y-111399D02*
G03X236840I-3559J159D01*
G01X236841Y-111418D02*
Y-111399D01*
G01X243957Y-111418D02*
X236841D01*
G01X248537Y-109748D02*
G03X249956Y-112031I2652J66D01*
G01X248537Y-108250D02*
Y-109748D01*
G01X250179Y-106359D02*
G03X248537Y-108249I2747J-4045D01*
G01X256884Y-107368D02*
G03X250178Y-106359I-4153J-4811D01*
G01X253611Y-107689D02*
G03X251080Y-107949I-869J-3992D01*
G01X251081Y-107948D02*
G03X250837Y-110104I805J-1183D01*
G01Y-110106D02*
G03X254306Y-111513I5270J8013D01*
G01X260954Y-116041D02*
Y-107954D01*
G01X254892Y-115895D02*
G03X255001Y-114328I-764J840D01*
G01X269619Y-117484D02*
Y-106797D01*
G01X269620Y-117484D02*
G03X271926I1153J198D01*
G01X266864Y-117375D02*
G03X266002Y-116329I-764J249D01*
G01X262978Y-115462D02*
G03X266002Y-116329I2046J1428D01*
G01X260955Y-116043D02*
G03X264164Y-118351I2956J725D01*
G01X265463Y-118350D02*
X264165D01*
G01X265464Y-118352D02*
G03X266864Y-117374I-24J1525D01*
G01X256906Y-116470D02*
G03X257054Y-113728I-3143J1545D01*
G01X254317Y-118340D02*
G03X256906Y-116470I-1259J4470D01*
G01X262978Y-107954D02*
Y-115463D01*
G01X257054Y-113729D02*
G03X254307Y-111513I-3470J-1490D01*
G01X271969Y-102342D02*
G03I-1194J0D01*
G01X271926Y-106797D02*
G03X269620I-1153J-409D01*
G01X266003Y-107954D02*
X262978D01*
G01X266004Y-107955D02*
G03X266008Y-105932I-177J1012D01*
G01X262978D02*
X266008D01*
G01X262971Y-103419D02*
X262978Y-105932D01*
G01X262972Y-103418D02*
G03X260954Y-103491I-1005J-141D01*
G01Y-105932D02*
Y-103492D01*
G01X259930Y-105932D02*
X260954D01*
G01X259930D02*
G03X259981Y-107955I298J-1005D01*
G01X260954Y-107954D02*
X259982D01*
G01X255606Y-108620D02*
G03X256885Y-107367I599J667D01*
G01X290671Y-110842D02*
G03X290703Y-118351I860J-3751D01*
G01X276837Y-114305D02*
G03X278891Y-116297I4069J2141D01*
G01X274529Y-113568D02*
G03X275888Y-116443I5718J944D01*
G01X275887D02*
G03X279572Y-118352I4392J3967D01*
G01X281425Y-118350D02*
X279571D01*
G01X281425D02*
G03X284525Y-117161I0J4636D01*
G01X285201Y-116508D02*
X284524Y-117161D01*
G01X285201Y-116508D02*
G03X283966Y-115211I-695J574D01*
G01X281510Y-116675D02*
G03X283966Y-115212I-989J4453D01*
G01X278889Y-116297D02*
G03X281508Y-116677I1946J4197D01*
G01X271926Y-106797D02*
Y-117484D01*
G01X274529Y-113566D02*
Y-111839D01*
G01X276446Y-112943D02*
G03X276837Y-114305I4162J458D01*
G01X276445Y-112066D02*
Y-112943D01*
G01X283833Y-109274D02*
G03X285403Y-108106I585J852D01*
G01X285402D02*
G03X280919Y-105777I-4776J-3714D01*
G01X279541D02*
X280919D01*
G01X279540D02*
G03X274999Y-109274I1260J-6333D01*
G01X274998D02*
G03X274529Y-111839I9988J-3152D01*
G01X276849Y-109932D02*
G03X276446Y-112066I5467J-2137D01*
G01X280036Y-107542D02*
G03X276849Y-109933I664J-4205D01*
G01X282662Y-108199D02*
G03X280037Y-107539I-2313J-3650D01*
G01X283833Y-109275D02*
G03X282662Y-108202I-9277J-8949D01*
G01X294457Y-116619D02*
G03Y-112289I-51J2165D01*
G01X291853Y-116620D02*
X294456D01*
G01X291853Y-112289D02*
G03Y-116619I195J-2165D01*
G01X294165Y-118350D02*
X290701D01*
G01X294165D02*
G03X296471Y-117226I-1088J5161D01*
G01X296473Y-117625D02*
Y-117226D01*
G01X296474Y-117627D02*
G03X298494I1010J185D01*
G01X298495Y-109394D02*
Y-117625D01*
G01X301067Y-108534D02*
Y-106508D01*
G01X301615Y-108534D02*
X301067D01*
G01X301615Y-106508D02*
Y-108534D01*
G01X302461Y-106508D02*
X301615D01*
G01X302461Y-106001D02*
Y-106508D01*
G01X300223Y-106001D02*
X302461D01*
G01X300223Y-106508D02*
Y-106001D01*
G01X301067Y-106508D02*
X300223D01*
G01X305164Y-106001D02*
X304731D01*
G01X305713Y-108544D02*
X305164Y-106001D01*
G01X305171Y-108544D02*
X305713D01*
G01X304889Y-106871D02*
X305171Y-108544D01*
G01X304309D02*
X304889Y-106871D01*
G01X304086Y-108544D02*
X304309D01*
G01X303501Y-106887D02*
X304086Y-108544D01*
G01X303226D02*
X303501Y-106887D01*
G01X302698Y-108544D02*
X303226D01*
G01X303243Y-106001D02*
X302698Y-108544D01*
G01X303648Y-106001D02*
X303243D01*
G01X304192Y-107632D02*
X303648Y-106001D01*
G01X304731D02*
X304192Y-107632D01*
G01X294456Y-112288D02*
X291853D01*
G01X296473Y-110841D02*
Y-109686D01*
G01X296472Y-110841D02*
G03X292878Y-110536I-3256J-17043D01*
G01X292879Y-110535D02*
G03X290670Y-110842I280J-10112D01*
G01X298496Y-109394D02*
G03X295031Y-105933I-3962J-501D01*
G01X291563Y-105932D02*
X295031D01*
G01X291562D02*
G03X289112Y-107085I584J-4421D01*
G01Y-107086D02*
G03X289820Y-108520I585J-603D01*
G01X290987Y-107954D02*
G03X289821Y-108520I1446J-4464D01*
G01X294740Y-107954D02*
X290987D01*
G01X296473Y-109686D02*
G03X294742Y-107955I-1598J133D01*
G01X381000Y-125000D02*
Y-133000D01*
X385000D01*
G01X391000Y-125000D02*
X390200Y-125267D01*
X389600Y-125933D01*
X389200Y-126733D01*
X388900Y-127800D01*
X388800Y-129000D01*
X388900Y-130200D01*
X389200Y-131267D01*
X389600Y-132067D01*
X390200Y-132733D01*
X391000Y-133000D01*
X391800Y-132733D01*
X392400Y-132067D01*
X392800Y-131267D01*
X393100Y-130200D01*
X393200Y-129000D01*
X393100Y-127800D01*
X392800Y-126733D01*
X392400Y-125933D01*
X391800Y-125267D01*
X391000Y-125000D01*
G01X397100Y-126333D02*
X397700Y-125533D01*
X398400Y-125133D01*
X399200Y-125000D01*
X400200Y-125267D01*
X400900Y-125933D01*
X401100Y-126733D01*
X401000Y-127534D01*
X400600Y-128200D01*
X398600Y-129533D01*
X397700Y-130467D01*
X397100Y-131800D01*
X396900Y-133000D01*
X401100D01*
G01X404000Y-135667D02*
X410000D01*
G01X415600Y-129000D02*
X417600D01*
Y-131400D01*
X417000Y-132200D01*
X416300Y-132733D01*
X415300Y-133000D01*
X414300Y-132733D01*
X413600Y-132200D01*
X413000Y-131400D01*
X412600Y-130467D01*
X412400Y-129400D01*
Y-128467D01*
X412600Y-127667D01*
X413000Y-126733D01*
X413600Y-125933D01*
X414200Y-125400D01*
X415000Y-125000D01*
X415700D01*
X416500Y-125267D01*
X417100Y-125800D01*
G01X420700Y-133000D02*
Y-125000D01*
X425300Y-133000D01*
Y-125000D01*
G01X428800Y-133000D02*
Y-125000D01*
X430800D01*
X431600Y-125400D01*
X432200Y-125933D01*
X432700Y-126733D01*
X433100Y-127667D01*
X433200Y-129000D01*
X433100Y-130333D01*
X432700Y-131267D01*
X432200Y-132067D01*
X431600Y-132600D01*
X430800Y-133000D01*
X428800D01*
G01X439000D02*
Y-125000D01*
X437800Y-126600D01*
G01Y-133000D02*
X440200D01*
G54D16*
X17500Y91000D03*
X17000Y204500D03*
X19900Y283000D03*
X16000Y302500D03*
Y307500D03*
X45500Y126000D03*
Y161000D03*
X42000Y236800D03*
X51772Y73600D03*
X47600Y68900D03*
X47000Y100000D03*
X61400Y104900D03*
X51772Y130500D03*
X53900Y157000D03*
X60600Y161200D03*
X51772Y187987D03*
X57500Y218500D03*
X51772Y245074D03*
X48500Y271500D03*
X57500Y289000D03*
X61489Y332329D03*
X63500Y359600D03*
X67700Y65000D03*
X66400Y77400D03*
X66000Y91100D03*
X69500Y100000D03*
X74593Y202207D03*
X71400Y221700D03*
X67500Y222900D03*
X71500Y247800D03*
X80148Y253648D03*
X72000Y335000D03*
X66000Y419000D03*
X88900Y67000D03*
X83300Y87100D03*
X94500Y105000D03*
X86600Y141300D03*
X85750Y202750D03*
X93032Y246477D03*
X87200Y258300D03*
X98700Y268300D03*
X95593Y333347D03*
X94000Y420000D03*
X83000Y417000D03*
X103800Y76240D03*
X98800Y272400D03*
X104500Y305500D03*
X99000Y350000D03*
X103000Y364000D03*
X106500D03*
X110000D03*
X115500Y389000D03*
X102500Y420000D03*
X119500Y57694D03*
X127500Y290500D03*
X125095Y306095D03*
X123500Y347500D03*
X120000Y364500D03*
X129000Y365000D03*
Y370500D03*
X120000Y368000D03*
Y371500D03*
X132000Y379000D03*
X118500D03*
X132000Y375500D03*
X127000Y397061D03*
X117000Y397000D03*
X121169Y396892D03*
X150860Y67400D03*
X145000Y296500D03*
X141000Y298500D03*
X142130Y325630D03*
X140900Y355400D03*
X142000Y350000D03*
X148000Y370000D03*
X140123Y391604D03*
X135500Y383000D03*
Y390500D03*
X140100Y395600D03*
X135500Y396000D03*
X165000Y294000D03*
X166150Y304050D03*
X166700Y338800D03*
X151000Y324200D03*
X159100Y350400D03*
X151500Y370000D03*
X168500Y294000D03*
X169850Y298950D03*
X178600Y378600D03*
Y374600D03*
X175100Y382600D03*
Y387100D03*
X174600Y401600D03*
Y406100D03*
Y410600D03*
X176000Y416000D03*
X192160Y77840D03*
X190000Y301500D03*
Y305500D03*
X189500Y319000D03*
X189000Y326000D03*
X191500Y413000D03*
X215000Y69000D03*
X220000D03*
X218000Y381100D03*
X217600Y415100D03*
X228500Y382500D03*
X221500Y378500D03*
X226000D03*
X221500Y415000D03*
X225600Y415100D03*
X229500Y415000D03*
X254000Y213500D03*
X241441Y215000D03*
X241900Y238800D03*
X272330Y54871D03*
X259500Y70100D03*
X271000Y184500D03*
X269000Y215000D03*
X259000Y223000D03*
X282200Y179121D03*
X275260Y223000D03*
X280500Y224300D03*
X288000Y293000D03*
X288500Y317000D03*
X303500Y69400D03*
X298500Y184500D03*
X292000Y294720D03*
X299500Y295500D03*
X301000Y312000D03*
X311000Y193500D03*
X312000Y217000D03*
X308967Y204000D03*
X312000Y234400D03*
X311600Y252400D03*
X314500Y276500D03*
X312000Y295500D03*
X321899Y343000D03*
X321300Y423600D03*
X324800Y415200D03*
X321300Y416700D03*
X324800Y410700D03*
X341500Y233500D03*
X340953Y237000D03*
X328500Y258900D03*
X330500Y291500D03*
X338000Y315000D03*
X326000Y374000D03*
X325300Y387200D03*
X331500Y376000D03*
X338500D03*
X342000D03*
X325300Y396200D03*
Y391700D03*
X354000Y128000D03*
X351000Y130500D03*
X353500D03*
X356000D03*
X350100Y169400D03*
X352600D03*
X357600D03*
X355100D03*
X347300Y179000D03*
X351200Y196600D03*
X350500Y229500D03*
X355000Y242500D03*
X354975Y247900D03*
X343500Y258900D03*
X349000Y303000D03*
X355500Y306500D03*
X360000Y402400D03*
X376838Y100230D03*
X367000Y126000D03*
X374300Y129000D03*
X371800D03*
X374300Y132000D03*
X371800D03*
X363600Y176600D03*
X367600Y169300D03*
X364700Y169400D03*
X369560Y213000D03*
X372060D03*
X367000D03*
X364500D03*
X367000Y232000D03*
X372500D03*
X360500Y243000D03*
X367000Y241243D03*
X369500Y267500D03*
X362300Y286100D03*
X365800D03*
X374800Y291100D03*
X370300D03*
X361500Y296100D03*
X365800Y291100D03*
X362100Y291000D03*
X363100Y418300D03*
X360311Y409880D03*
X363100Y422800D03*
X384000Y102980D03*
Y109500D03*
X379800Y177100D03*
X380000Y204500D03*
X378000Y273500D03*
X388650Y292650D03*
X378000Y293200D03*
X383000D03*
X393300Y312500D03*
X383000Y341500D03*
X384300Y368700D03*
X383900Y372600D03*
X407000Y120000D03*
X399500D03*
X399000Y221407D03*
Y225000D03*
X397800Y259300D03*
X403700D03*
X399800Y278400D03*
X409100Y281300D03*
X409300Y286300D03*
X409200Y291700D03*
X397500Y312900D03*
X407500Y305000D03*
X397300Y320700D03*
X398000Y352000D03*
X410000Y358543D03*
X409650Y403950D03*
X412350Y401250D03*
Y397150D03*
X409650Y394450D03*
X422000Y77500D03*
X413500Y88500D03*
X423000Y100500D03*
X427800Y100300D03*
X429400Y107500D03*
X417500Y352000D03*
X419150Y394450D03*
X416450Y401250D03*
Y397150D03*
X419150Y403950D03*
X434500Y77000D03*
X441400Y78100D03*
X433500Y100500D03*
X444200D03*
X431000Y116500D03*
X444000Y226000D03*
Y250000D03*
X439500Y266500D03*
X444000Y263000D03*
X447200Y347500D03*
X446000Y374500D03*
X431000Y416000D03*
X448430Y89540D03*
X463500Y86500D03*
X450000Y108200D03*
X454600Y108500D03*
X462000Y224500D03*
Y250000D03*
X460000Y284500D03*
Y289500D03*
X459500Y322000D03*
X459000Y326000D03*
X454000Y393500D03*
Y397000D03*
X450000Y407000D03*
X481000Y70700D03*
X479867Y138867D03*
X481500Y182016D03*
X478000Y198000D03*
X471000Y259200D03*
X477500Y259000D03*
X471000Y347000D03*
X471400Y363300D03*
X489400Y126300D03*
X493300Y121500D03*
X496000Y167500D03*
Y179258D03*
X496500Y192500D03*
X496000Y205500D03*
X492500Y272200D03*
X491800Y277700D03*
X503950Y143000D03*
X512100Y249500D03*
X507100Y240700D03*
X512100D03*
Y244700D03*
Y262500D03*
X512300Y254400D03*
X512200Y258700D03*
X512650Y268150D03*
X511900Y276200D03*
X508950Y273250D03*
X506100Y280600D03*
X505000Y379500D03*
X504500Y376000D03*
X533000Y87000D03*
X533500Y124500D03*
X534000Y160500D03*
X517000Y212500D03*
X533200Y220000D03*
X529800Y223000D03*
X530350Y257480D03*
X532500Y272500D03*
X532900Y318900D03*
X527600D03*
X532400Y340600D03*
Y345600D03*
X527100Y340600D03*
Y345600D03*
X532200Y377700D03*
X523700Y384100D03*
X528200Y377700D03*
X523700D03*
X525176Y411925D03*
X543957Y60543D03*
X537000Y69000D03*
X534500Y130000D03*
Y136500D03*
X534600Y148300D03*
Y152000D03*
X544000Y159000D03*
X542500Y189500D03*
X538500D03*
X540900Y201500D03*
X543500Y205000D03*
X536900Y201500D03*
X549000Y267500D03*
X551700Y256300D03*
X541346Y303507D03*
X538600Y318900D03*
X538100Y340600D03*
Y345600D03*
X548557Y387700D03*
X538500Y407875D03*
X543000Y396700D03*
X562500Y74600D03*
X560650Y70450D03*
X559941Y62120D03*
X563341Y62102D03*
X564350Y65350D03*
X559000Y85000D03*
X560200Y81500D03*
X559000Y88800D03*
X568700Y204300D03*
X564700Y204400D03*
X553800Y240200D03*
X563700Y352400D03*
X564500Y379000D03*
X560200Y386500D03*
X580500Y65800D03*
X580643Y60900D03*
X585900Y79600D03*
X576459Y161971D03*
X575072Y165500D03*
X580500Y194500D03*
X583000Y192000D03*
X573200Y204300D03*
X586500Y230000D03*
X581500Y267000D03*
X581400Y292250D03*
X580300Y356700D03*
X576300Y371200D03*
X580200Y361700D03*
X580100Y366700D03*
X580300Y380700D03*
Y375700D03*
Y385700D03*
X599000Y92500D03*
X592000Y136000D03*
X597703Y187000D03*
X616500Y194874D03*
X614100Y224100D03*
X610500Y227000D03*
X622000Y136000D03*
X633500Y196874D03*
X636000Y216142D03*
X626989Y237989D03*
X633500Y301500D03*
X647000Y113500D03*
M02*
